(kicad_sch
	(version 20250114)
	(generator "eeschema")
	(generator_version "9.0")
	(paper "A3")
	(title_block
		(title "OCuLink to 10GbE adapter")
		(date "2026-02-23")
		(rev "1.1.0")
		(company "Antmicro Ltd")
		(comment 1 "www.antmicro.com")
	)
	(text "[place on bottom]"
		(exclude_from_sim no)
		(at 388.62 212.09 0)
		(effects
			(font
				(size 1.27 1.27)
			)
		)
	)
	(text "1V DC-DC"
		(exclude_from_sim no)
		(at 172.72 132.08 0)
		(effects
			(font
				(size 2.54 2.54)
				(thickness 0.508)
				(bold yes)
			)
		)
	)
	(text "3V3"
		(exclude_from_sim no)
		(at 210.566 19.558 0)
		(effects
			(font
				(size 1.27 1.27)
			)
		)
	)
	(text "5V internal LDO"
		(exclude_from_sim no)
		(at 271.272 143.764 0)
		(effects
			(font
				(size 1.27 1.27)
			)
		)
	)
	(text "-->"
		(exclude_from_sim no)
		(at 246.634 19.304 0)
		(effects
			(font
				(size 1.27 1.27)
			)
		)
	)
	(text "DVDD (1V0)"
		(exclude_from_sim no)
		(at 265.938 19.558 0)
		(effects
			(font
				(size 1.27 1.27)
			)
		)
	)
	(text "max 100ms"
		(exclude_from_sim no)
		(at 215.646 18.288 0)
		(effects
			(font
				(size 0.635 0.635)
			)
		)
	)
	(text "3V3 DC-DC"
		(exclude_from_sim no)
		(at 172.72 17.78 0)
		(effects
			(font
				(size 2.54 2.54)
				(thickness 0.508)
				(bold yes)
			)
		)
	)
	(text "Power Inputs"
		(exclude_from_sim no)
		(at 82.804 63.5 0)
		(effects
			(font
				(size 2.54 2.54)
				(thickness 0.508)
				(bold yes)
			)
		)
	)
	(text "1V88 DC-DC"
		(exclude_from_sim no)
		(at 172.72 93.98 0)
		(effects
			(font
				(size 2.54 2.54)
				(thickness 0.508)
				(bold yes)
			)
		)
	)
	(text "5V internal LDO"
		(exclude_from_sim no)
		(at 271.272 181.864 0)
		(effects
			(font
				(size 1.27 1.27)
			)
		)
	)
	(text "PGOOD LED"
		(exclude_from_sim no)
		(at 295.656 226.314 0)
		(effects
			(font
				(size 1.27 1.27)
			)
		)
	)
	(text "1V88"
		(exclude_from_sim no)
		(at 241.046 19.558 0)
		(effects
			(font
				(size 1.27 1.27)
			)
		)
	)
	(text "UVLO\n3V3 rail is first in \nthe power sequence,\nso deasserting its\nenable pin \nturns off remainng \nDC-DC converters"
		(exclude_from_sim no)
		(at 179.07 39.37 0)
		(effects
			(font
				(size 1.27 1.27)
			)
		)
	)
	(text "-->"
		(exclude_from_sim no)
		(at 215.646 19.304 0)
		(effects
			(font
				(size 1.27 1.27)
			)
		)
	)
	(text "1V0"
		(exclude_from_sim no)
		(at 252.476 19.558 0)
		(effects
			(font
				(size 1.27 1.27)
			)
		)
	)
	(text "VCCD (0.92V)"
		(exclude_from_sim no)
		(at 225.806 19.558 0)
		(effects
			(font
				(size 1.27 1.27)
			)
		)
	)
	(text "5V internal LDO"
		(exclude_from_sim no)
		(at 271.272 67.564 0)
		(effects
			(font
				(size 1.27 1.27)
			)
		)
	)
	(text "V_{OUT} = 0.6 x (1 + R_{H}/R_{L}) [V]"
		(exclude_from_sim no)
		(at 160.02 200.66 0)
		(effects
			(font
				(size 1.27 1.27)
			)
			(justify left)
		)
	)
	(text "-->"
		(exclude_from_sim no)
		(at 257.556 19.304 0)
		(effects
			(font
				(size 1.27 1.27)
			)
		)
	)
	(text "5V internal LDO"
		(exclude_from_sim no)
		(at 271.272 29.464 0)
		(effects
			(font
				(size 1.27 1.27)
			)
		)
	)
	(text "0V92 DC-DC"
		(exclude_from_sim no)
		(at 172.72 55.88 0)
		(effects
			(font
				(size 2.54 2.54)
				(thickness 0.508)
				(bold yes)
			)
		)
	)
	(text "-->"
		(exclude_from_sim no)
		(at 235.204 19.304 0)
		(effects
			(font
				(size 1.27 1.27)
			)
		)
	)
	(text "DVDD DC-DC"
		(exclude_from_sim no)
		(at 172.72 170.18 0)
		(effects
			(font
				(size 2.54 2.54)
				(thickness 0.508)
				(bold yes)
			)
		)
	)
	(text "5V@3A"
		(exclude_from_sim no)
		(at 57.15 116.84 0)
		(effects
			(font
				(size 1.27 1.27)
			)
		)
	)
	(text "ICT Testpoints"
		(exclude_from_sim no)
		(at 388.62 208.28 0)
		(effects
			(font
				(size 2.54 2.54)
				(thickness 0.508)
				(bold yes)
			)
		)
	)
	(text "5V internal LDO"
		(exclude_from_sim no)
		(at 271.272 105.664 0)
		(effects
			(font
				(size 1.27 1.27)
			)
		)
	)
	(junction
		(at 391.16 25.4)
		(diameter 0)
		(color 0 0 0 0)
	)
	(junction
		(at 350.52 25.4)
		(diameter 0)
		(color 0 0 0 0)
	)
	(junction
		(at 67.31 120.65)
		(diameter 0)
		(color 0 0 0 0)
	)
	(junction
		(at 58.42 85.09)
		(diameter 0)
		(color 0 0 0 0)
	)
	(junction
		(at 307.34 25.4)
		(diameter 0)
		(color 0 0 0 0)
	)
	(junction
		(at 332.74 101.6)
		(diameter 0)
		(color 0 0 0 0)
	)
	(junction
		(at 74.93 85.09)
		(diameter 0)
		(color 0 0 0 0)
	)
	(junction
		(at 350.52 139.7)
		(diameter 0)
		(color 0 0 0 0)
	)
	(junction
		(at 350.52 177.8)
		(diameter 0)
		(color 0 0 0 0)
	)
	(junction
		(at 391.16 63.5)
		(diameter 0)
		(color 0 0 0 0)
	)
	(junction
		(at 83.82 85.09)
		(diameter 0)
		(color 0 0 0 0)
	)
	(junction
		(at 327.66 149.86)
		(diameter 0)
		(color 0 0 0 0)
	)
	(junction
		(at 217.17 177.8)
		(diameter 0)
		(color 0 0 0 0)
	)
	(junction
		(at 332.74 25.4)
		(diameter 0)
		(color 0 0 0 0)
	)
	(junction
		(at 138.43 85.09)
		(diameter 0)
		(color 0 0 0 0)
	)
	(junction
		(at 259.08 78.74)
		(diameter 0)
		(color 0 0 0 0)
	)
	(junction
		(at 237.49 177.8)
		(diameter 0)
		(color 0 0 0 0)
	)
	(junction
		(at 354.33 25.4)
		(diameter 0)
		(color 0 0 0 0)
	)
	(junction
		(at 350.52 63.5)
		(diameter 0)
		(color 0 0 0 0)
	)
	(junction
		(at 344.17 177.8)
		(diameter 0)
		(color 0 0 0 0)
	)
	(junction
		(at 217.17 101.6)
		(diameter 0)
		(color 0 0 0 0)
	)
	(junction
		(at 259.08 116.84)
		(diameter 0)
		(color 0 0 0 0)
	)
	(junction
		(at 64.77 85.09)
		(diameter 0)
		(color 0 0 0 0)
	)
	(junction
		(at 217.17 139.7)
		(diameter 0)
		(color 0 0 0 0)
	)
	(junction
		(at 314.96 240.03)
		(diameter 0)
		(color 0 0 0 0)
	)
	(junction
		(at 327.66 139.7)
		(diameter 0)
		(color 0 0 0 0)
	)
	(junction
		(at 327.66 25.4)
		(diameter 0)
		(color 0 0 0 0)
	)
	(junction
		(at 332.74 73.66)
		(diameter 0)
		(color 0 0 0 0)
	)
	(junction
		(at 391.16 139.7)
		(diameter 0)
		(color 0 0 0 0)
	)
	(junction
		(at 67.31 153.67)
		(diameter 0)
		(color 0 0 0 0)
	)
	(junction
		(at 74.93 120.65)
		(diameter 0)
		(color 0 0 0 0)
	)
	(junction
		(at 256.54 66.04)
		(diameter 0)
		(color 0 0 0 0)
	)
	(junction
		(at 327.66 177.8)
		(diameter 0)
		(color 0 0 0 0)
	)
	(junction
		(at 237.49 101.6)
		(diameter 0)
		(color 0 0 0 0)
	)
	(junction
		(at 307.34 177.8)
		(diameter 0)
		(color 0 0 0 0)
	)
	(junction
		(at 237.49 25.4)
		(diameter 0)
		(color 0 0 0 0)
	)
	(junction
		(at 227.33 25.4)
		(diameter 0)
		(color 0 0 0 0)
	)
	(junction
		(at 203.2 215.9)
		(diameter 0)
		(color 0 0 0 0)
	)
	(junction
		(at 227.33 63.5)
		(diameter 0)
		(color 0 0 0 0)
	)
	(junction
		(at 332.74 111.76)
		(diameter 0)
		(color 0 0 0 0)
	)
	(junction
		(at 332.74 35.56)
		(diameter 0)
		(color 0 0 0 0)
	)
	(junction
		(at 237.49 139.7)
		(diameter 0)
		(color 0 0 0 0)
	)
	(junction
		(at 374.65 177.8)
		(diameter 0)
		(color 0 0 0 0)
	)
	(junction
		(at 53.34 170.18)
		(diameter 0)
		(color 0 0 0 0)
	)
	(junction
		(at 354.33 139.7)
		(diameter 0)
		(color 0 0 0 0)
	)
	(junction
		(at 391.16 177.8)
		(diameter 0)
		(color 0 0 0 0)
	)
	(junction
		(at 364.49 63.5)
		(diameter 0)
		(color 0 0 0 0)
	)
	(junction
		(at 217.17 25.4)
		(diameter 0)
		(color 0 0 0 0)
	)
	(junction
		(at 196.85 34.29)
		(diameter 0)
		(color 0 0 0 0)
	)
	(junction
		(at 256.54 104.14)
		(diameter 0)
		(color 0 0 0 0)
	)
	(junction
		(at 374.65 139.7)
		(diameter 0)
		(color 0 0 0 0)
	)
	(junction
		(at 344.17 63.5)
		(diameter 0)
		(color 0 0 0 0)
	)
	(junction
		(at 364.49 177.8)
		(diameter 0)
		(color 0 0 0 0)
	)
	(junction
		(at 133.35 85.09)
		(diameter 0)
		(color 0 0 0 0)
	)
	(junction
		(at 256.54 27.94)
		(diameter 0)
		(color 0 0 0 0)
	)
	(junction
		(at 124.46 85.09)
		(diameter 0)
		(color 0 0 0 0)
	)
	(junction
		(at 354.33 63.5)
		(diameter 0)
		(color 0 0 0 0)
	)
	(junction
		(at 332.74 63.5)
		(diameter 0)
		(color 0 0 0 0)
	)
	(junction
		(at 177.8 215.9)
		(diameter 0)
		(color 0 0 0 0)
	)
	(junction
		(at 256.54 180.34)
		(diameter 0)
		(color 0 0 0 0)
	)
	(junction
		(at 196.85 25.4)
		(diameter 0)
		(color 0 0 0 0)
	)
	(junction
		(at 374.65 101.6)
		(diameter 0)
		(color 0 0 0 0)
	)
	(junction
		(at 344.17 25.4)
		(diameter 0)
		(color 0 0 0 0)
	)
	(junction
		(at 358.14 25.4)
		(diameter 0)
		(color 0 0 0 0)
	)
	(junction
		(at 307.34 101.6)
		(diameter 0)
		(color 0 0 0 0)
	)
	(junction
		(at 374.65 63.5)
		(diameter 0)
		(color 0 0 0 0)
	)
	(junction
		(at 227.33 177.8)
		(diameter 0)
		(color 0 0 0 0)
	)
	(junction
		(at 327.66 63.5)
		(diameter 0)
		(color 0 0 0 0)
	)
	(junction
		(at 332.74 149.86)
		(diameter 0)
		(color 0 0 0 0)
	)
	(junction
		(at 91.44 120.65)
		(diameter 0)
		(color 0 0 0 0)
	)
	(junction
		(at 354.33 101.6)
		(diameter 0)
		(color 0 0 0 0)
	)
	(junction
		(at 350.52 101.6)
		(diameter 0)
		(color 0 0 0 0)
	)
	(junction
		(at 358.14 177.8)
		(diameter 0)
		(color 0 0 0 0)
	)
	(junction
		(at 143.51 85.09)
		(diameter 0)
		(color 0 0 0 0)
	)
	(junction
		(at 256.54 142.24)
		(diameter 0)
		(color 0 0 0 0)
	)
	(junction
		(at 344.17 139.7)
		(diameter 0)
		(color 0 0 0 0)
	)
	(junction
		(at 358.14 101.6)
		(diameter 0)
		(color 0 0 0 0)
	)
	(junction
		(at 364.49 101.6)
		(diameter 0)
		(color 0 0 0 0)
	)
	(junction
		(at 237.49 63.5)
		(diameter 0)
		(color 0 0 0 0)
	)
	(junction
		(at 358.14 63.5)
		(diameter 0)
		(color 0 0 0 0)
	)
	(junction
		(at 256.54 193.04)
		(diameter 0)
		(color 0 0 0 0)
	)
	(junction
		(at 327.66 73.66)
		(diameter 0)
		(color 0 0 0 0)
	)
	(junction
		(at 364.49 25.4)
		(diameter 0)
		(color 0 0 0 0)
	)
	(junction
		(at 354.33 177.8)
		(diameter 0)
		(color 0 0 0 0)
	)
	(junction
		(at 259.08 40.64)
		(diameter 0)
		(color 0 0 0 0)
	)
	(junction
		(at 227.33 101.6)
		(diameter 0)
		(color 0 0 0 0)
	)
	(junction
		(at 364.49 139.7)
		(diameter 0)
		(color 0 0 0 0)
	)
	(junction
		(at 44.45 90.17)
		(diameter 0)
		(color 0 0 0 0)
	)
	(junction
		(at 327.66 35.56)
		(diameter 0)
		(color 0 0 0 0)
	)
	(junction
		(at 307.34 139.7)
		(diameter 0)
		(color 0 0 0 0)
	)
	(junction
		(at 391.16 101.6)
		(diameter 0)
		(color 0 0 0 0)
	)
	(junction
		(at 217.17 63.5)
		(diameter 0)
		(color 0 0 0 0)
	)
	(junction
		(at 344.17 101.6)
		(diameter 0)
		(color 0 0 0 0)
	)
	(junction
		(at 332.74 139.7)
		(diameter 0)
		(color 0 0 0 0)
	)
	(junction
		(at 307.34 63.5)
		(diameter 0)
		(color 0 0 0 0)
	)
	(junction
		(at 53.34 160.02)
		(diameter 0)
		(color 0 0 0 0)
	)
	(junction
		(at 227.33 139.7)
		(diameter 0)
		(color 0 0 0 0)
	)
	(junction
		(at 327.66 111.76)
		(diameter 0)
		(color 0 0 0 0)
	)
	(junction
		(at 358.14 139.7)
		(diameter 0)
		(color 0 0 0 0)
	)
	(junction
		(at 332.74 177.8)
		(diameter 0)
		(color 0 0 0 0)
	)
	(junction
		(at 259.08 154.94)
		(diameter 0)
		(color 0 0 0 0)
	)
	(junction
		(at 327.66 187.96)
		(diameter 0)
		(color 0 0 0 0)
	)
	(junction
		(at 64.77 120.65)
		(diameter 0)
		(color 0 0 0 0)
	)
	(junction
		(at 327.66 101.6)
		(diameter 0)
		(color 0 0 0 0)
	)
	(junction
		(at 332.74 187.96)
		(diameter 0)
		(color 0 0 0 0)
	)
	(junction
		(at 374.65 25.4)
		(diameter 0)
		(color 0 0 0 0)
	)
	(junction
		(at 254 215.9)
		(diameter 0)
		(color 0 0 0 0)
	)
	(junction
		(at 228.6 215.9)
		(diameter 0)
		(color 0 0 0 0)
	)
	(no_connect
		(at 50.8 138.43)
	)
	(no_connect
		(at 50.8 140.97)
	)
	(no_connect
		(at 50.8 133.35)
	)
	(no_connect
		(at 50.8 148.59)
	)
	(no_connect
		(at 50.8 135.89)
	)
	(no_connect
		(at 50.8 146.05)
	)
	(wire
		(pts
			(xy 81.28 172.72) (xy 81.28 149.86)
		)
		(stroke
			(width 0)
			(type default)
		)
	)
	(wire
		(pts
			(xy 327.66 101.6) (xy 327.66 104.14)
		)
		(stroke
			(width 0)
			(type default)
		)
	)
	(wire
		(pts
			(xy 124.46 85.09) (xy 133.35 85.09)
		)
		(stroke
			(width 0)
			(type default)
		)
	)
	(wire
		(pts
			(xy 133.35 82.55) (xy 133.35 85.09)
		)
		(stroke
			(width 0)
			(type default)
		)
	)
	(wire
		(pts
			(xy 256.54 205.74) (xy 256.54 193.04)
		)
		(stroke
			(width 0)
			(type default)
		)
	)
	(wire
		(pts
			(xy 358.14 24.13) (xy 358.14 25.4)
		)
		(stroke
			(width 0)
			(type default)
		)
	)
	(wire
		(pts
			(xy 354.33 25.4) (xy 358.14 25.4)
		)
		(stroke
			(width 0)
			(type default)
		)
	)
	(wire
		(pts
			(xy 344.17 195.58) (xy 344.17 190.5)
		)
		(stroke
			(width 0)
			(type default)
		)
	)
	(wire
		(pts
			(xy 64.77 83.82) (xy 64.77 85.09)
		)
		(stroke
			(width 0)
			(type default)
		)
	)
	(wire
		(pts
			(xy 384.81 101.6) (xy 391.16 101.6)
		)
		(stroke
			(width 0)
			(type default)
		)
	)
	(wire
		(pts
			(xy 320.04 177.8) (xy 327.66 177.8)
		)
		(stroke
			(width 0)
			(type default)
		)
	)
	(wire
		(pts
			(xy 256.54 152.4) (xy 256.54 154.94)
		)
		(stroke
			(width 0)
			(type default)
		)
	)
	(wire
		(pts
			(xy 177.8 215.9) (xy 203.2 215.9)
		)
		(stroke
			(width 0)
			(type default)
		)
	)
	(wire
		(pts
			(xy 138.43 85.09) (xy 143.51 85.09)
		)
		(stroke
			(width 0)
			(type default)
		)
	)
	(wire
		(pts
			(xy 91.44 120.65) (xy 96.52 120.65)
		)
		(stroke
			(width 0)
			(type default)
		)
	)
	(wire
		(pts
			(xy 227.33 139.7) (xy 237.49 139.7)
		)
		(stroke
			(width 0)
			(type default)
		)
	)
	(wire
		(pts
			(xy 124.46 83.82) (xy 124.46 85.09)
		)
		(stroke
			(width 0)
			(type default)
		)
	)
	(wire
		(pts
			(xy 358.14 63.5) (xy 364.49 63.5)
		)
		(stroke
			(width 0)
			(type default)
		)
	)
	(polyline
		(pts
			(xy 157.48 127) (xy 407.67 127)
		)
		(stroke
			(width 0)
			(type dash)
		)
	)
	(wire
		(pts
			(xy 350.52 138.43) (xy 350.52 139.7)
		)
		(stroke
			(width 0)
			(type default)
		)
	)
	(wire
		(pts
			(xy 254 215.9) (xy 254 218.44)
		)
		(stroke
			(width 0)
			(type default)
		)
	)
	(wire
		(pts
			(xy 237.49 139.7) (xy 276.86 139.7)
		)
		(stroke
			(width 0)
			(type default)
		)
	)
	(wire
		(pts
			(xy 294.64 106.68) (xy 307.34 106.68)
		)
		(stroke
			(width 0)
			(type default)
		)
	)
	(polyline
		(pts
			(xy 157.48 88.9) (xy 407.67 88.9)
		)
		(stroke
			(width 0)
			(type dash)
		)
	)
	(wire
		(pts
			(xy 203.2 215.9) (xy 203.2 218.44)
		)
		(stroke
			(width 0)
			(type default)
		)
	)
	(wire
		(pts
			(xy 74.93 118.11) (xy 74.93 120.65)
		)
		(stroke
			(width 0)
			(type default)
		)
	)
	(wire
		(pts
			(xy 166.37 215.9) (xy 177.8 215.9)
		)
		(stroke
			(width 0)
			(type default)
		)
	)
	(wire
		(pts
			(xy 217.17 101.6) (xy 227.33 101.6)
		)
		(stroke
			(width 0)
			(type default)
		)
	)
	(wire
		(pts
			(xy 203.2 223.52) (xy 203.2 226.06)
		)
		(stroke
			(width 0)
			(type default)
		)
	)
	(wire
		(pts
			(xy 50.8 125.73) (xy 81.28 125.73)
		)
		(stroke
			(width 0)
			(type default)
		)
	)
	(wire
		(pts
			(xy 327.66 177.8) (xy 327.66 180.34)
		)
		(stroke
			(width 0)
			(type default)
		)
	)
	(wire
		(pts
			(xy 400.05 101.6) (xy 400.05 99.06)
		)
		(stroke
			(width 0)
			(type default)
		)
	)
	(wire
		(pts
			(xy 304.8 231.14) (xy 304.8 228.6)
		)
		(stroke
			(width 0)
			(type default)
		)
	)
	(wire
		(pts
			(xy 227.33 139.7) (xy 227.33 147.32)
		)
		(stroke
			(width 0)
			(type default)
		)
	)
	(wire
		(pts
			(xy 256.54 180.34) (xy 276.86 180.34)
		)
		(stroke
			(width 0)
			(type default)
		)
	)
	(wire
		(pts
			(xy 279.4 233.68) (xy 279.4 231.14)
		)
		(stroke
			(width 0)
			(type default)
		)
	)
	(wire
		(pts
			(xy 332.74 147.32) (xy 332.74 149.86)
		)
		(stroke
			(width 0)
			(type default)
		)
	)
	(wire
		(pts
			(xy 344.17 63.5) (xy 350.52 63.5)
		)
		(stroke
			(width 0)
			(type default)
		)
	)
	(wire
		(pts
			(xy 344.17 139.7) (xy 344.17 147.32)
		)
		(stroke
			(width 0)
			(type default)
		)
	)
	(wire
		(pts
			(xy 294.64 182.88) (xy 307.34 182.88)
		)
		(stroke
			(width 0)
			(type default)
		)
	)
	(wire
		(pts
			(xy 50.8 156.21) (xy 53.34 156.21)
		)
		(stroke
			(width 0)
			(type default)
		)
	)
	(wire
		(pts
			(xy 259.08 154.94) (xy 276.86 154.94)
		)
		(stroke
			(width 0)
			(type default)
		)
	)
	(wire
		(pts
			(xy 227.33 157.48) (xy 227.33 152.4)
		)
		(stroke
			(width 0)
			(type default)
		)
	)
	(wire
		(pts
			(xy 374.65 177.8) (xy 374.65 185.42)
		)
		(stroke
			(width 0)
			(type default)
		)
	)
	(wire
		(pts
			(xy 247.65 66.04) (xy 256.54 66.04)
		)
		(stroke
			(width 0)
			(type default)
		)
	)
	(wire
		(pts
			(xy 332.74 177.8) (xy 332.74 180.34)
		)
		(stroke
			(width 0)
			(type default)
		)
	)
	(wire
		(pts
			(xy 259.08 111.76) (xy 261.62 111.76)
		)
		(stroke
			(width 0)
			(type default)
		)
	)
	(wire
		(pts
			(xy 297.18 119.38) (xy 297.18 116.84)
		)
		(stroke
			(width 0)
			(type default)
		)
	)
	(wire
		(pts
			(xy 237.49 119.38) (xy 237.49 114.3)
		)
		(stroke
			(width 0)
			(type default)
		)
	)
	(wire
		(pts
			(xy 344.17 25.4) (xy 344.17 33.02)
		)
		(stroke
			(width 0)
			(type default)
		)
	)
	(wire
		(pts
			(xy 379.73 223.52) (xy 391.16 223.52)
		)
		(stroke
			(width 0)
			(type default)
		)
	)
	(wire
		(pts
			(xy 391.16 139.7) (xy 400.05 139.7)
		)
		(stroke
			(width 0)
			(type default)
		)
	)
	(wire
		(pts
			(xy 74.93 82.55) (xy 74.93 85.09)
		)
		(stroke
			(width 0)
			(type default)
		)
	)
	(wire
		(pts
			(xy 121.92 85.09) (xy 124.46 85.09)
		)
		(stroke
			(width 0)
			(type default)
		)
	)
	(wire
		(pts
			(xy 332.74 177.8) (xy 327.66 177.8)
		)
		(stroke
			(width 0)
			(type default)
		)
	)
	(polyline
		(pts
			(xy 157.48 203.2) (xy 407.67 203.2)
		)
		(stroke
			(width 0)
			(type dash)
		)
	)
	(wire
		(pts
			(xy 391.16 25.4) (xy 400.05 25.4)
		)
		(stroke
			(width 0)
			(type default)
		)
	)
	(wire
		(pts
			(xy 327.66 109.22) (xy 327.66 111.76)
		)
		(stroke
			(width 0)
			(type default)
		)
	)
	(wire
		(pts
			(xy 266.7 111.76) (xy 276.86 111.76)
		)
		(stroke
			(width 0)
			(type default)
		)
	)
	(wire
		(pts
			(xy 364.49 177.8) (xy 364.49 185.42)
		)
		(stroke
			(width 0)
			(type default)
		)
	)
	(wire
		(pts
			(xy 391.16 99.06) (xy 391.16 101.6)
		)
		(stroke
			(width 0)
			(type default)
		)
	)
	(wire
		(pts
			(xy 217.17 177.8) (xy 217.17 185.42)
		)
		(stroke
			(width 0)
			(type default)
		)
	)
	(wire
		(pts
			(xy 379.73 220.98) (xy 391.16 220.98)
		)
		(stroke
			(width 0)
			(type default)
		)
	)
	(wire
		(pts
			(xy 58.42 91.44) (xy 58.42 85.09)
		)
		(stroke
			(width 0)
			(type default)
		)
	)
	(wire
		(pts
			(xy 259.08 40.64) (xy 256.54 40.64)
		)
		(stroke
			(width 0)
			(type default)
		)
	)
	(wire
		(pts
			(xy 256.54 114.3) (xy 256.54 116.84)
		)
		(stroke
			(width 0)
			(type default)
		)
	)
	(wire
		(pts
			(xy 354.33 81.28) (xy 354.33 76.2)
		)
		(stroke
			(width 0)
			(type default)
		)
	)
	(wire
		(pts
			(xy 297.18 154.94) (xy 294.64 154.94)
		)
		(stroke
			(width 0)
			(type default)
		)
	)
	(wire
		(pts
			(xy 384.81 139.7) (xy 391.16 139.7)
		)
		(stroke
			(width 0)
			(type default)
		)
	)
	(wire
		(pts
			(xy 374.65 101.6) (xy 374.65 109.22)
		)
		(stroke
			(width 0)
			(type default)
		)
	)
	(wire
		(pts
			(xy 358.14 138.43) (xy 358.14 139.7)
		)
		(stroke
			(width 0)
			(type default)
		)
	)
	(wire
		(pts
			(xy 354.33 101.6) (xy 358.14 101.6)
		)
		(stroke
			(width 0)
			(type default)
		)
	)
	(wire
		(pts
			(xy 391.16 231.14) (xy 387.35 231.14)
		)
		(stroke
			(width 0)
			(type default)
		)
	)
	(wire
		(pts
			(xy 332.74 25.4) (xy 327.66 25.4)
		)
		(stroke
			(width 0)
			(type default)
		)
	)
	(wire
		(pts
			(xy 320.04 63.5) (xy 327.66 63.5)
		)
		(stroke
			(width 0)
			(type default)
		)
	)
	(wire
		(pts
			(xy 227.33 177.8) (xy 227.33 185.42)
		)
		(stroke
			(width 0)
			(type default)
		)
	)
	(wire
		(pts
			(xy 227.33 119.38) (xy 227.33 114.3)
		)
		(stroke
			(width 0)
			(type default)
		)
	)
	(wire
		(pts
			(xy 227.33 63.5) (xy 227.33 71.12)
		)
		(stroke
			(width 0)
			(type default)
		)
	)
	(wire
		(pts
			(xy 327.66 139.7) (xy 327.66 142.24)
		)
		(stroke
			(width 0)
			(type default)
		)
	)
	(wire
		(pts
			(xy 400.05 63.5) (xy 400.05 60.96)
		)
		(stroke
			(width 0)
			(type default)
		)
	)
	(wire
		(pts
			(xy 228.6 215.9) (xy 254 215.9)
		)
		(stroke
			(width 0)
			(type default)
		)
	)
	(wire
		(pts
			(xy 320.04 25.4) (xy 327.66 25.4)
		)
		(stroke
			(width 0)
			(type default)
		)
	)
	(wire
		(pts
			(xy 294.64 68.58) (xy 307.34 68.58)
		)
		(stroke
			(width 0)
			(type default)
		)
	)
	(wire
		(pts
			(xy 48.26 167.64) (xy 48.26 170.18)
		)
		(stroke
			(width 0)
			(type default)
		)
	)
	(wire
		(pts
			(xy 247.65 81.28) (xy 247.65 76.2)
		)
		(stroke
			(width 0)
			(type default)
		)
	)
	(wire
		(pts
			(xy 332.74 71.12) (xy 332.74 73.66)
		)
		(stroke
			(width 0)
			(type default)
		)
	)
	(wire
		(pts
			(xy 279.4 223.52) (xy 279.4 226.06)
		)
		(stroke
			(width 0)
			(type default)
		)
	)
	(wire
		(pts
			(xy 256.54 193.04) (xy 276.86 193.04)
		)
		(stroke
			(width 0)
			(type default)
		)
	)
	(wire
		(pts
			(xy 327.66 73.66) (xy 332.74 73.66)
		)
		(stroke
			(width 0)
			(type default)
		)
	)
	(wire
		(pts
			(xy 364.49 177.8) (xy 374.65 177.8)
		)
		(stroke
			(width 0)
			(type default)
		)
	)
	(wire
		(pts
			(xy 256.54 27.94) (xy 276.86 27.94)
		)
		(stroke
			(width 0)
			(type default)
		)
	)
	(wire
		(pts
			(xy 254 215.9) (xy 279.4 215.9)
		)
		(stroke
			(width 0)
			(type default)
		)
	)
	(wire
		(pts
			(xy 332.74 25.4) (xy 344.17 25.4)
		)
		(stroke
			(width 0)
			(type default)
		)
	)
	(wire
		(pts
			(xy 76.2 144.78) (xy 76.2 128.27)
		)
		(stroke
			(width 0)
			(type default)
		)
	)
	(wire
		(pts
			(xy 332.74 187.96) (xy 332.74 189.23)
		)
		(stroke
			(width 0)
			(type default)
		)
	)
	(wire
		(pts
			(xy 266.7 187.96) (xy 276.86 187.96)
		)
		(stroke
			(width 0)
			(type default)
		)
	)
	(wire
		(pts
			(xy 374.65 119.38) (xy 374.65 114.3)
		)
		(stroke
			(width 0)
			(type default)
		)
	)
	(wire
		(pts
			(xy 227.33 177.8) (xy 237.49 177.8)
		)
		(stroke
			(width 0)
			(type default)
		)
	)
	(wire
		(pts
			(xy 358.14 62.23) (xy 358.14 63.5)
		)
		(stroke
			(width 0)
			(type default)
		)
	)
	(wire
		(pts
			(xy 332.74 41.91) (xy 332.74 43.18)
		)
		(stroke
			(width 0)
			(type default)
		)
	)
	(wire
		(pts
			(xy 53.34 167.64) (xy 53.34 170.18)
		)
		(stroke
			(width 0)
			(type default)
		)
	)
	(wire
		(pts
			(xy 256.54 104.14) (xy 276.86 104.14)
		)
		(stroke
			(width 0)
			(type default)
		)
	)
	(wire
		(pts
			(xy 327.66 185.42) (xy 327.66 187.96)
		)
		(stroke
			(width 0)
			(type default)
		)
	)
	(wire
		(pts
			(xy 67.31 137.16) (xy 67.31 120.65)
		)
		(stroke
			(width 0)
			(type default)
		)
	)
	(wire
		(pts
			(xy 58.42 85.09) (xy 64.77 85.09)
		)
		(stroke
			(width 0)
			(type default)
		)
	)
	(wire
		(pts
			(xy 133.35 85.09) (xy 138.43 85.09)
		)
		(stroke
			(width 0)
			(type default)
		)
	)
	(wire
		(pts
			(xy 259.08 73.66) (xy 261.62 73.66)
		)
		(stroke
			(width 0)
			(type default)
		)
	)
	(wire
		(pts
			(xy 237.49 81.28) (xy 237.49 76.2)
		)
		(stroke
			(width 0)
			(type default)
		)
	)
	(wire
		(pts
			(xy 332.74 25.4) (xy 332.74 27.94)
		)
		(stroke
			(width 0)
			(type default)
		)
	)
	(wire
		(pts
			(xy 364.49 119.38) (xy 364.49 114.3)
		)
		(stroke
			(width 0)
			(type default)
		)
	)
	(wire
		(pts
			(xy 217.17 137.16) (xy 217.17 139.7)
		)
		(stroke
			(width 0)
			(type default)
		)
	)
	(wire
		(pts
			(xy 354.33 63.5) (xy 354.33 71.12)
		)
		(stroke
			(width 0)
			(type default)
		)
	)
	(wire
		(pts
			(xy 358.14 139.7) (xy 364.49 139.7)
		)
		(stroke
			(width 0)
			(type default)
		)
	)
	(wire
		(pts
			(xy 247.65 27.94) (xy 256.54 27.94)
		)
		(stroke
			(width 0)
			(type default)
		)
	)
	(wire
		(pts
			(xy 44.45 87.63) (xy 44.45 90.17)
		)
		(stroke
			(width 0)
			(type default)
		)
	)
	(wire
		(pts
			(xy 259.08 40.64) (xy 276.86 40.64)
		)
		(stroke
			(width 0)
			(type default)
		)
	)
	(wire
		(pts
			(xy 344.17 63.5) (xy 344.17 71.12)
		)
		(stroke
			(width 0)
			(type default)
		)
	)
	(wire
		(pts
			(xy 256.54 142.24) (xy 276.86 142.24)
		)
		(stroke
			(width 0)
			(type default)
		)
	)
	(wire
		(pts
			(xy 297.18 193.04) (xy 294.64 193.04)
		)
		(stroke
			(width 0)
			(type default)
		)
	)
	(wire
		(pts
			(xy 391.16 238.76) (xy 387.35 238.76)
		)
		(stroke
			(width 0)
			(type default)
		)
	)
	(wire
		(pts
			(xy 374.65 63.5) (xy 374.65 71.12)
		)
		(stroke
			(width 0)
			(type default)
		)
	)
	(wire
		(pts
			(xy 294.64 73.66) (xy 327.66 73.66)
		)
		(stroke
			(width 0)
			(type default)
		)
	)
	(wire
		(pts
			(xy 332.74 118.11) (xy 332.74 119.38)
		)
		(stroke
			(width 0)
			(type default)
		)
	)
	(wire
		(pts
			(xy 53.34 156.21) (xy 53.34 160.02)
		)
		(stroke
			(width 0)
			(type default)
		)
	)
	(wire
		(pts
			(xy 332.74 33.02) (xy 332.74 35.56)
		)
		(stroke
			(width 0)
			(type default)
		)
	)
	(wire
		(pts
			(xy 332.74 111.76) (xy 332.74 113.03)
		)
		(stroke
			(width 0)
			(type default)
		)
	)
	(wire
		(pts
			(xy 320.04 139.7) (xy 327.66 139.7)
		)
		(stroke
			(width 0)
			(type default)
		)
	)
	(wire
		(pts
			(xy 196.85 31.75) (xy 196.85 34.29)
		)
		(stroke
			(width 0)
			(type default)
		)
	)
	(polyline
		(pts
			(xy 157.48 165.1) (xy 407.67 165.1)
		)
		(stroke
			(width 0)
			(type dash)
		)
	)
	(wire
		(pts
			(xy 346.71 243.84) (xy 346.71 246.38)
		)
		(stroke
			(width 0)
			(type default)
		)
	)
	(wire
		(pts
			(xy 67.31 153.67) (xy 67.31 172.72)
		)
		(stroke
			(width 0)
			(type default)
		)
	)
	(wire
		(pts
			(xy 254 243.84) (xy 254 246.38)
		)
		(stroke
			(width 0)
			(type default)
		)
	)
	(wire
		(pts
			(xy 228.6 243.84) (xy 228.6 246.38)
		)
		(stroke
			(width 0)
			(type default)
		)
	)
	(wire
		(pts
			(xy 314.96 139.7) (xy 307.34 139.7)
		)
		(stroke
			(width 0)
			(type default)
		)
	)
	(wire
		(pts
			(xy 350.52 24.13) (xy 350.52 25.4)
		)
		(stroke
			(width 0)
			(type default)
		)
	)
	(wire
		(pts
			(xy 53.34 160.02) (xy 53.34 162.56)
		)
		(stroke
			(width 0)
			(type default)
		)
	)
	(wire
		(pts
			(xy 350.52 63.5) (xy 354.33 63.5)
		)
		(stroke
			(width 0)
			(type default)
		)
	)
	(wire
		(pts
			(xy 64.77 119.38) (xy 64.77 120.65)
		)
		(stroke
			(width 0)
			(type default)
		)
	)
	(wire
		(pts
			(xy 48.26 162.56) (xy 48.26 160.02)
		)
		(stroke
			(width 0)
			(type default)
		)
	)
	(wire
		(pts
			(xy 332.74 35.56) (xy 332.74 36.83)
		)
		(stroke
			(width 0)
			(type default)
		)
	)
	(wire
		(pts
			(xy 48.26 160.02) (xy 53.34 160.02)
		)
		(stroke
			(width 0)
			(type default)
		)
	)
	(wire
		(pts
			(xy 364.49 81.28) (xy 364.49 76.2)
		)
		(stroke
			(width 0)
			(type default)
		)
	)
	(wire
		(pts
			(xy 254 223.52) (xy 254 226.06)
		)
		(stroke
			(width 0)
			(type default)
		)
	)
	(wire
		(pts
			(xy 400.05 22.86) (xy 400.05 25.4)
		)
		(stroke
			(width 0)
			(type default)
		)
	)
	(wire
		(pts
			(xy 294.64 101.6) (xy 307.34 101.6)
		)
		(stroke
			(width 0)
			(type default)
		)
	)
	(wire
		(pts
			(xy 237.49 63.5) (xy 276.86 63.5)
		)
		(stroke
			(width 0)
			(type default)
		)
	)
	(wire
		(pts
			(xy 374.65 157.48) (xy 374.65 152.4)
		)
		(stroke
			(width 0)
			(type default)
		)
	)
	(wire
		(pts
			(xy 217.17 195.58) (xy 217.17 190.5)
		)
		(stroke
			(width 0)
			(type default)
		)
	)
	(wire
		(pts
			(xy 41.91 85.09) (xy 58.42 85.09)
		)
		(stroke
			(width 0)
			(type default)
		)
	)
	(wire
		(pts
			(xy 74.93 85.09) (xy 83.82 85.09)
		)
		(stroke
			(width 0)
			(type default)
		)
	)
	(wire
		(pts
			(xy 332.74 63.5) (xy 332.74 66.04)
		)
		(stroke
			(width 0)
			(type default)
		)
	)
	(wire
		(pts
			(xy 350.52 177.8) (xy 354.33 177.8)
		)
		(stroke
			(width 0)
			(type default)
		)
	)
	(wire
		(pts
			(xy 354.33 195.58) (xy 354.33 190.5)
		)
		(stroke
			(width 0)
			(type default)
		)
	)
	(wire
		(pts
			(xy 374.65 63.5) (xy 379.73 63.5)
		)
		(stroke
			(width 0)
			(type default)
		)
	)
	(wire
		(pts
			(xy 294.64 139.7) (xy 307.34 139.7)
		)
		(stroke
			(width 0)
			(type default)
		)
	)
	(wire
		(pts
			(xy 304.8 220.98) (xy 304.8 223.52)
		)
		(stroke
			(width 0)
			(type default)
		)
	)
	(wire
		(pts
			(xy 297.18 78.74) (xy 294.64 78.74)
		)
		(stroke
			(width 0)
			(type default)
		)
	)
	(wire
		(pts
			(xy 391.16 233.68) (xy 387.35 233.68)
		)
		(stroke
			(width 0)
			(type default)
		)
	)
	(wire
		(pts
			(xy 247.65 157.48) (xy 247.65 152.4)
		)
		(stroke
			(width 0)
			(type default)
		)
	)
	(polyline
		(pts
			(xy 368.3 252.73) (xy 368.3 203.2)
		)
		(stroke
			(width 0)
			(type dash)
		)
	)
	(wire
		(pts
			(xy 354.33 101.6) (xy 354.33 109.22)
		)
		(stroke
			(width 0)
			(type default)
		)
	)
	(wire
		(pts
			(xy 259.08 187.96) (xy 261.62 187.96)
		)
		(stroke
			(width 0)
			(type default)
		)
	)
	(wire
		(pts
			(xy 358.14 177.8) (xy 364.49 177.8)
		)
		(stroke
			(width 0)
			(type default)
		)
	)
	(wire
		(pts
			(xy 327.66 149.86) (xy 332.74 149.86)
		)
		(stroke
			(width 0)
			(type default)
		)
	)
	(wire
		(pts
			(xy 332.74 63.5) (xy 327.66 63.5)
		)
		(stroke
			(width 0)
			(type default)
		)
	)
	(wire
		(pts
			(xy 327.66 71.12) (xy 327.66 73.66)
		)
		(stroke
			(width 0)
			(type default)
		)
	)
	(polyline
		(pts
			(xy 157.48 50.8) (xy 407.67 50.8)
		)
		(stroke
			(width 0)
			(type dash)
		)
	)
	(wire
		(pts
			(xy 237.49 195.58) (xy 237.49 190.5)
		)
		(stroke
			(width 0)
			(type default)
		)
	)
	(wire
		(pts
			(xy 332.74 149.86) (xy 332.74 151.13)
		)
		(stroke
			(width 0)
			(type default)
		)
	)
	(wire
		(pts
			(xy 354.33 25.4) (xy 354.33 33.02)
		)
		(stroke
			(width 0)
			(type default)
		)
	)
	(wire
		(pts
			(xy 391.16 228.6) (xy 387.35 228.6)
		)
		(stroke
			(width 0)
			(type default)
		)
	)
	(wire
		(pts
			(xy 364.49 101.6) (xy 374.65 101.6)
		)
		(stroke
			(width 0)
			(type default)
		)
	)
	(wire
		(pts
			(xy 177.8 223.52) (xy 177.8 226.06)
		)
		(stroke
			(width 0)
			(type default)
		)
	)
	(wire
		(pts
			(xy 64.77 120.65) (xy 67.31 120.65)
		)
		(stroke
			(width 0)
			(type default)
		)
	)
	(polyline
		(pts
			(xy 157.48 284.48) (xy 157.48 12.7)
		)
		(stroke
			(width 0)
			(type dash)
		)
	)
	(wire
		(pts
			(xy 53.34 170.18) (xy 53.34 172.72)
		)
		(stroke
			(width 0)
			(type default)
		)
	)
	(wire
		(pts
			(xy 358.14 25.4) (xy 364.49 25.4)
		)
		(stroke
			(width 0)
			(type default)
		)
	)
	(wire
		(pts
			(xy 400.05 139.7) (xy 400.05 137.16)
		)
		(stroke
			(width 0)
			(type default)
		)
	)
	(wire
		(pts
			(xy 297.18 195.58) (xy 297.18 193.04)
		)
		(stroke
			(width 0)
			(type default)
		)
	)
	(wire
		(pts
			(xy 322.58 240.03) (xy 339.09 240.03)
		)
		(stroke
			(width 0)
			(type default)
		)
	)
	(wire
		(pts
			(xy 391.16 63.5) (xy 400.05 63.5)
		)
		(stroke
			(width 0)
			(type default)
		)
	)
	(wire
		(pts
			(xy 327.66 33.02) (xy 327.66 35.56)
		)
		(stroke
			(width 0)
			(type default)
		)
	)
	(wire
		(pts
			(xy 259.08 116.84) (xy 276.86 116.84)
		)
		(stroke
			(width 0)
			(type default)
		)
	)
	(wire
		(pts
			(xy 217.17 99.06) (xy 217.17 101.6)
		)
		(stroke
			(width 0)
			(type default)
		)
	)
	(wire
		(pts
			(xy 217.17 139.7) (xy 227.33 139.7)
		)
		(stroke
			(width 0)
			(type default)
		)
	)
	(wire
		(pts
			(xy 344.17 101.6) (xy 344.17 109.22)
		)
		(stroke
			(width 0)
			(type default)
		)
	)
	(wire
		(pts
			(xy 227.33 195.58) (xy 227.33 190.5)
		)
		(stroke
			(width 0)
			(type default)
		)
	)
	(wire
		(pts
			(xy 217.17 43.18) (xy 217.17 38.1)
		)
		(stroke
			(width 0)
			(type default)
		)
	)
	(wire
		(pts
			(xy 269.24 35.56) (xy 276.86 35.56)
		)
		(stroke
			(width 0)
			(type default)
		)
	)
	(wire
		(pts
			(xy 354.33 157.48) (xy 354.33 152.4)
		)
		(stroke
			(width 0)
			(type default)
		)
	)
	(wire
		(pts
			(xy 177.8 215.9) (xy 177.8 218.44)
		)
		(stroke
			(width 0)
			(type default)
		)
	)
	(wire
		(pts
			(xy 247.65 142.24) (xy 256.54 142.24)
		)
		(stroke
			(width 0)
			(type default)
		)
	)
	(wire
		(pts
			(xy 50.8 120.65) (xy 64.77 120.65)
		)
		(stroke
			(width 0)
			(type default)
		)
	)
	(wire
		(pts
			(xy 234.95 238.76) (xy 246.38 238.76)
		)
		(stroke
			(width 0)
			(type default)
		)
	)
	(wire
		(pts
			(xy 237.49 177.8) (xy 237.49 185.42)
		)
		(stroke
			(width 0)
			(type default)
		)
	)
	(wire
		(pts
			(xy 91.44 147.32) (xy 91.44 149.86)
		)
		(stroke
			(width 0)
			(type default)
		)
	)
	(wire
		(pts
			(xy 358.14 101.6) (xy 364.49 101.6)
		)
		(stroke
			(width 0)
			(type default)
		)
	)
	(wire
		(pts
			(xy 196.85 22.86) (xy 196.85 25.4)
		)
		(stroke
			(width 0)
			(type default)
		)
	)
	(wire
		(pts
			(xy 50.8 128.27) (xy 76.2 128.27)
		)
		(stroke
			(width 0)
			(type default)
		)
	)
	(wire
		(pts
			(xy 314.96 25.4) (xy 307.34 25.4)
		)
		(stroke
			(width 0)
			(type default)
		)
	)
	(wire
		(pts
			(xy 364.49 157.48) (xy 364.49 152.4)
		)
		(stroke
			(width 0)
			(type default)
		)
	)
	(wire
		(pts
			(xy 358.14 176.53) (xy 358.14 177.8)
		)
		(stroke
			(width 0)
			(type default)
		)
	)
	(wire
		(pts
			(xy 228.6 223.52) (xy 228.6 226.06)
		)
		(stroke
			(width 0)
			(type default)
		)
	)
	(wire
		(pts
			(xy 374.65 177.8) (xy 379.73 177.8)
		)
		(stroke
			(width 0)
			(type default)
		)
	)
	(wire
		(pts
			(xy 217.17 25.4) (xy 217.17 33.02)
		)
		(stroke
			(width 0)
			(type default)
		)
	)
	(wire
		(pts
			(xy 327.66 147.32) (xy 327.66 149.86)
		)
		(stroke
			(width 0)
			(type default)
		)
	)
	(wire
		(pts
			(xy 256.54 116.84) (xy 259.08 116.84)
		)
		(stroke
			(width 0)
			(type default)
		)
	)
	(wire
		(pts
			(xy 354.33 177.8) (xy 354.33 185.42)
		)
		(stroke
			(width 0)
			(type default)
		)
	)
	(wire
		(pts
			(xy 344.17 157.48) (xy 344.17 152.4)
		)
		(stroke
			(width 0)
			(type default)
		)
	)
	(wire
		(pts
			(xy 350.52 62.23) (xy 350.52 63.5)
		)
		(stroke
			(width 0)
			(type default)
		)
	)
	(wire
		(pts
			(xy 247.65 185.42) (xy 247.65 180.34)
		)
		(stroke
			(width 0)
			(type default)
		)
	)
	(wire
		(pts
			(xy 259.08 78.74) (xy 259.08 111.76)
		)
		(stroke
			(width 0)
			(type default)
		)
	)
	(wire
		(pts
			(xy 44.45 90.17) (xy 44.45 102.87)
		)
		(stroke
			(width 0)
			(type default)
		)
	)
	(wire
		(pts
			(xy 196.85 25.4) (xy 217.17 25.4)
		)
		(stroke
			(width 0)
			(type default)
		)
	)
	(wire
		(pts
			(xy 320.04 101.6) (xy 327.66 101.6)
		)
		(stroke
			(width 0)
			(type default)
		)
	)
	(wire
		(pts
			(xy 294.64 30.48) (xy 307.34 30.48)
		)
		(stroke
			(width 0)
			(type default)
		)
	)
	(wire
		(pts
			(xy 259.08 116.84) (xy 259.08 149.86)
		)
		(stroke
			(width 0)
			(type default)
		)
	)
	(wire
		(pts
			(xy 354.33 177.8) (xy 358.14 177.8)
		)
		(stroke
			(width 0)
			(type default)
		)
	)
	(wire
		(pts
			(xy 196.85 26.67) (xy 196.85 25.4)
		)
		(stroke
			(width 0)
			(type default)
		)
	)
	(wire
		(pts
			(xy 237.49 43.18) (xy 237.49 38.1)
		)
		(stroke
			(width 0)
			(type default)
		)
	)
	(wire
		(pts
			(xy 327.66 111.76) (xy 332.74 111.76)
		)
		(stroke
			(width 0)
			(type default)
		)
	)
	(wire
		(pts
			(xy 332.74 80.01) (xy 332.74 81.28)
		)
		(stroke
			(width 0)
			(type default)
		)
	)
	(wire
		(pts
			(xy 217.17 101.6) (xy 217.17 109.22)
		)
		(stroke
			(width 0)
			(type default)
		)
	)
	(wire
		(pts
			(xy 237.49 157.48) (xy 237.49 152.4)
		)
		(stroke
			(width 0)
			(type default)
		)
	)
	(wire
		(pts
			(xy 344.17 43.18) (xy 344.17 38.1)
		)
		(stroke
			(width 0)
			(type default)
		)
	)
	(wire
		(pts
			(xy 217.17 60.96) (xy 217.17 63.5)
		)
		(stroke
			(width 0)
			(type default)
		)
	)
	(wire
		(pts
			(xy 384.81 177.8) (xy 391.16 177.8)
		)
		(stroke
			(width 0)
			(type default)
		)
	)
	(wire
		(pts
			(xy 391.16 226.06) (xy 387.35 226.06)
		)
		(stroke
			(width 0)
			(type default)
		)
	)
	(wire
		(pts
			(xy 247.65 71.12) (xy 247.65 66.04)
		)
		(stroke
			(width 0)
			(type default)
		)
	)
	(wire
		(pts
			(xy 256.54 66.04) (xy 256.54 71.12)
		)
		(stroke
			(width 0)
			(type default)
		)
	)
	(wire
		(pts
			(xy 344.17 139.7) (xy 350.52 139.7)
		)
		(stroke
			(width 0)
			(type default)
		)
	)
	(wire
		(pts
			(xy 74.93 120.65) (xy 91.44 120.65)
		)
		(stroke
			(width 0)
			(type default)
		)
	)
	(wire
		(pts
			(xy 364.49 139.7) (xy 364.49 147.32)
		)
		(stroke
			(width 0)
			(type default)
		)
	)
	(wire
		(pts
			(xy 259.08 78.74) (xy 276.86 78.74)
		)
		(stroke
			(width 0)
			(type default)
		)
	)
	(wire
		(pts
			(xy 256.54 142.24) (xy 256.54 147.32)
		)
		(stroke
			(width 0)
			(type default)
		)
	)
	(wire
		(pts
			(xy 227.33 101.6) (xy 237.49 101.6)
		)
		(stroke
			(width 0)
			(type default)
		)
	)
	(wire
		(pts
			(xy 314.96 240.03) (xy 317.5 240.03)
		)
		(stroke
			(width 0)
			(type default)
		)
	)
	(wire
		(pts
			(xy 256.54 190.5) (xy 256.54 193.04)
		)
		(stroke
			(width 0)
			(type default)
		)
	)
	(wire
		(pts
			(xy 256.54 104.14) (xy 256.54 109.22)
		)
		(stroke
			(width 0)
			(type default)
		)
	)
	(wire
		(pts
			(xy 364.49 101.6) (xy 364.49 109.22)
		)
		(stroke
			(width 0)
			(type default)
		)
	)
	(wire
		(pts
			(xy 237.49 25.4) (xy 276.86 25.4)
		)
		(stroke
			(width 0)
			(type default)
		)
	)
	(wire
		(pts
			(xy 143.51 82.55) (xy 143.51 85.09)
		)
		(stroke
			(width 0)
			(type default)
		)
	)
	(wire
		(pts
			(xy 294.64 35.56) (xy 327.66 35.56)
		)
		(stroke
			(width 0)
			(type default)
		)
	)
	(wire
		(pts
			(xy 350.52 25.4) (xy 354.33 25.4)
		)
		(stroke
			(width 0)
			(type default)
		)
	)
	(wire
		(pts
			(xy 217.17 81.28) (xy 217.17 76.2)
		)
		(stroke
			(width 0)
			(type default)
		)
	)
	(wire
		(pts
			(xy 332.74 194.31) (xy 332.74 195.58)
		)
		(stroke
			(width 0)
			(type default)
		)
	)
	(wire
		(pts
			(xy 121.92 120.65) (xy 143.51 120.65)
		)
		(stroke
			(width 0)
			(type default)
		)
	)
	(wire
		(pts
			(xy 227.33 43.18) (xy 227.33 38.1)
		)
		(stroke
			(width 0)
			(type default)
		)
	)
	(wire
		(pts
			(xy 314.96 205.74) (xy 256.54 205.74)
		)
		(stroke
			(width 0)
			(type default)
		)
	)
	(wire
		(pts
			(xy 237.49 101.6) (xy 237.49 109.22)
		)
		(stroke
			(width 0)
			(type default)
		)
	)
	(wire
		(pts
			(xy 350.52 176.53) (xy 350.52 177.8)
		)
		(stroke
			(width 0)
			(type default)
		)
	)
	(wire
		(pts
			(xy 83.82 85.09) (xy 83.82 87.63)
		)
		(stroke
			(width 0)
			(type default)
		)
	)
	(wire
		(pts
			(xy 332.74 139.7) (xy 332.74 142.24)
		)
		(stroke
			(width 0)
			(type default)
		)
	)
	(wire
		(pts
			(xy 259.08 40.64) (xy 259.08 73.66)
		)
		(stroke
			(width 0)
			(type default)
		)
	)
	(wire
		(pts
			(xy 259.08 149.86) (xy 261.62 149.86)
		)
		(stroke
			(width 0)
			(type default)
		)
	)
	(wire
		(pts
			(xy 196.85 41.91) (xy 196.85 43.18)
		)
		(stroke
			(width 0)
			(type default)
		)
	)
	(wire
		(pts
			(xy 237.49 139.7) (xy 237.49 147.32)
		)
		(stroke
			(width 0)
			(type default)
		)
	)
	(wire
		(pts
			(xy 256.54 180.34) (xy 256.54 185.42)
		)
		(stroke
			(width 0)
			(type default)
		)
	)
	(wire
		(pts
			(xy 217.17 157.48) (xy 217.17 152.4)
		)
		(stroke
			(width 0)
			(type default)
		)
	)
	(wire
		(pts
			(xy 67.31 120.65) (xy 74.93 120.65)
		)
		(stroke
			(width 0)
			(type default)
		)
	)
	(wire
		(pts
			(xy 364.49 139.7) (xy 374.65 139.7)
		)
		(stroke
			(width 0)
			(type default)
		)
	)
	(wire
		(pts
			(xy 364.49 63.5) (xy 364.49 71.12)
		)
		(stroke
			(width 0)
			(type default)
		)
	)
	(wire
		(pts
			(xy 327.66 63.5) (xy 327.66 66.04)
		)
		(stroke
			(width 0)
			(type default)
		)
	)
	(wire
		(pts
			(xy 67.31 142.24) (xy 67.31 153.67)
		)
		(stroke
			(width 0)
			(type default)
		)
	)
	(wire
		(pts
			(xy 307.34 63.5) (xy 294.64 63.5)
		)
		(stroke
			(width 0)
			(type default)
		)
	)
	(wire
		(pts
			(xy 256.54 27.94) (xy 256.54 33.02)
		)
		(stroke
			(width 0)
			(type default)
		)
	)
	(wire
		(pts
			(xy 374.65 25.4) (xy 374.65 33.02)
		)
		(stroke
			(width 0)
			(type default)
		)
	)
	(wire
		(pts
			(xy 256.54 78.74) (xy 259.08 78.74)
		)
		(stroke
			(width 0)
			(type default)
		)
	)
	(wire
		(pts
			(xy 344.17 63.5) (xy 332.74 63.5)
		)
		(stroke
			(width 0)
			(type default)
		)
	)
	(wire
		(pts
			(xy 217.17 25.4) (xy 227.33 25.4)
		)
		(stroke
			(width 0)
			(type default)
		)
	)
	(wire
		(pts
			(xy 354.33 63.5) (xy 358.14 63.5)
		)
		(stroke
			(width 0)
			(type default)
		)
	)
	(wire
		(pts
			(xy 279.4 215.9) (xy 279.4 218.44)
		)
		(stroke
			(width 0)
			(type default)
		)
	)
	(wire
		(pts
			(xy 256.54 66.04) (xy 276.86 66.04)
		)
		(stroke
			(width 0)
			(type default)
		)
	)
	(wire
		(pts
			(xy 364.49 195.58) (xy 364.49 190.5)
		)
		(stroke
			(width 0)
			(type default)
		)
	)
	(wire
		(pts
			(xy 247.65 43.18) (xy 247.65 38.1)
		)
		(stroke
			(width 0)
			(type default)
		)
	)
	(wire
		(pts
			(xy 374.65 25.4) (xy 379.73 25.4)
		)
		(stroke
			(width 0)
			(type default)
		)
	)
	(wire
		(pts
			(xy 344.17 177.8) (xy 332.74 177.8)
		)
		(stroke
			(width 0)
			(type default)
		)
	)
	(wire
		(pts
			(xy 354.33 139.7) (xy 354.33 147.32)
		)
		(stroke
			(width 0)
			(type default)
		)
	)
	(wire
		(pts
			(xy 203.2 215.9) (xy 228.6 215.9)
		)
		(stroke
			(width 0)
			(type default)
		)
	)
	(wire
		(pts
			(xy 138.43 87.63) (xy 138.43 85.09)
		)
		(stroke
			(width 0)
			(type default)
		)
	)
	(wire
		(pts
			(xy 237.49 25.4) (xy 237.49 33.02)
		)
		(stroke
			(width 0)
			(type default)
		)
	)
	(wire
		(pts
			(xy 297.18 157.48) (xy 297.18 154.94)
		)
		(stroke
			(width 0)
			(type default)
		)
	)
	(wire
		(pts
			(xy 50.8 153.67) (xy 67.31 153.67)
		)
		(stroke
			(width 0)
			(type default)
		)
	)
	(wire
		(pts
			(xy 294.64 111.76) (xy 327.66 111.76)
		)
		(stroke
			(width 0)
			(type default)
		)
	)
	(wire
		(pts
			(xy 344.17 25.4) (xy 350.52 25.4)
		)
		(stroke
			(width 0)
			(type default)
		)
	)
	(wire
		(pts
			(xy 217.17 119.38) (xy 217.17 114.3)
		)
		(stroke
			(width 0)
			(type default)
		)
	)
	(wire
		(pts
			(xy 209.55 238.76) (xy 220.98 238.76)
		)
		(stroke
			(width 0)
			(type default)
		)
	)
	(wire
		(pts
			(xy 203.2 243.84) (xy 203.2 246.38)
		)
		(stroke
			(width 0)
			(type default)
		)
	)
	(wire
		(pts
			(xy 354.33 139.7) (xy 358.14 139.7)
		)
		(stroke
			(width 0)
			(type default)
		)
	)
	(wire
		(pts
			(xy 247.65 33.02) (xy 247.65 27.94)
		)
		(stroke
			(width 0)
			(type default)
		)
	)
	(wire
		(pts
			(xy 81.28 144.78) (xy 81.28 125.73)
		)
		(stroke
			(width 0)
			(type default)
		)
	)
	(wire
		(pts
			(xy 227.33 101.6) (xy 227.33 109.22)
		)
		(stroke
			(width 0)
			(type default)
		)
	)
	(wire
		(pts
			(xy 247.65 104.14) (xy 256.54 104.14)
		)
		(stroke
			(width 0)
			(type default)
		)
	)
	(wire
		(pts
			(xy 307.34 101.6) (xy 314.96 101.6)
		)
		(stroke
			(width 0)
			(type default)
		)
	)
	(wire
		(pts
			(xy 364.49 25.4) (xy 374.65 25.4)
		)
		(stroke
			(width 0)
			(type default)
		)
	)
	(wire
		(pts
			(xy 374.65 81.28) (xy 374.65 76.2)
		)
		(stroke
			(width 0)
			(type default)
		)
	)
	(wire
		(pts
			(xy 256.54 76.2) (xy 256.54 78.74)
		)
		(stroke
			(width 0)
			(type default)
		)
	)
	(wire
		(pts
			(xy 332.74 73.66) (xy 332.74 74.93)
		)
		(stroke
			(width 0)
			(type default)
		)
	)
	(wire
		(pts
			(xy 332.74 139.7) (xy 327.66 139.7)
		)
		(stroke
			(width 0)
			(type default)
		)
	)
	(wire
		(pts
			(xy 247.65 119.38) (xy 247.65 114.3)
		)
		(stroke
			(width 0)
			(type default)
		)
	)
	(wire
		(pts
			(xy 217.17 177.8) (xy 227.33 177.8)
		)
		(stroke
			(width 0)
			(type default)
		)
	)
	(wire
		(pts
			(xy 327.66 25.4) (xy 327.66 27.94)
		)
		(stroke
			(width 0)
			(type default)
		)
	)
	(wire
		(pts
			(xy 332.74 185.42) (xy 332.74 187.96)
		)
		(stroke
			(width 0)
			(type default)
		)
	)
	(wire
		(pts
			(xy 227.33 25.4) (xy 237.49 25.4)
		)
		(stroke
			(width 0)
			(type default)
		)
	)
	(wire
		(pts
			(xy 391.16 101.6) (xy 400.05 101.6)
		)
		(stroke
			(width 0)
			(type default)
		)
	)
	(wire
		(pts
			(xy 247.65 180.34) (xy 256.54 180.34)
		)
		(stroke
			(width 0)
			(type default)
		)
	)
	(wire
		(pts
			(xy 196.85 34.29) (xy 196.85 36.83)
		)
		(stroke
			(width 0)
			(type default)
		)
	)
	(wire
		(pts
			(xy 350.52 101.6) (xy 354.33 101.6)
		)
		(stroke
			(width 0)
			(type default)
		)
	)
	(wire
		(pts
			(xy 217.17 139.7) (xy 217.17 147.32)
		)
		(stroke
			(width 0)
			(type default)
		)
	)
	(wire
		(pts
			(xy 76.2 172.72) (xy 76.2 149.86)
		)
		(stroke
			(width 0)
			(type default)
		)
	)
	(wire
		(pts
			(xy 294.64 187.96) (xy 327.66 187.96)
		)
		(stroke
			(width 0)
			(type default)
		)
	)
	(wire
		(pts
			(xy 354.33 43.18) (xy 354.33 38.1)
		)
		(stroke
			(width 0)
			(type default)
		)
	)
	(wire
		(pts
			(xy 332.74 109.22) (xy 332.74 111.76)
		)
		(stroke
			(width 0)
			(type default)
		)
	)
	(wire
		(pts
			(xy 350.52 100.33) (xy 350.52 101.6)
		)
		(stroke
			(width 0)
			(type default)
		)
	)
	(wire
		(pts
			(xy 364.49 25.4) (xy 364.49 33.02)
		)
		(stroke
			(width 0)
			(type default)
		)
	)
	(wire
		(pts
			(xy 358.14 100.33) (xy 358.14 101.6)
		)
		(stroke
			(width 0)
			(type default)
		)
	)
	(wire
		(pts
			(xy 294.64 177.8) (xy 307.34 177.8)
		)
		(stroke
			(width 0)
			(type default)
		)
	)
	(wire
		(pts
			(xy 228.6 215.9) (xy 228.6 218.44)
		)
		(stroke
			(width 0)
			(type default)
		)
	)
	(wire
		(pts
			(xy 350.52 139.7) (xy 354.33 139.7)
		)
		(stroke
			(width 0)
			(type default)
		)
	)
	(wire
		(pts
			(xy 307.34 177.8) (xy 314.96 177.8)
		)
		(stroke
			(width 0)
			(type default)
		)
	)
	(wire
		(pts
			(xy 384.81 25.4) (xy 391.16 25.4)
		)
		(stroke
			(width 0)
			(type default)
		)
	)
	(wire
		(pts
			(xy 391.16 236.22) (xy 387.35 236.22)
		)
		(stroke
			(width 0)
			(type default)
		)
	)
	(wire
		(pts
			(xy 297.18 116.84) (xy 294.64 116.84)
		)
		(stroke
			(width 0)
			(type default)
		)
	)
	(wire
		(pts
			(xy 184.15 238.76) (xy 195.58 238.76)
		)
		(stroke
			(width 0)
			(type default)
		)
	)
	(wire
		(pts
			(xy 314.96 63.5) (xy 307.34 63.5)
		)
		(stroke
			(width 0)
			(type default)
		)
	)
	(wire
		(pts
			(xy 294.64 144.78) (xy 307.34 144.78)
		)
		(stroke
			(width 0)
			(type default)
		)
	)
	(wire
		(pts
			(xy 266.7 73.66) (xy 276.86 73.66)
		)
		(stroke
			(width 0)
			(type default)
		)
	)
	(wire
		(pts
			(xy 196.85 34.29) (xy 207.01 34.29)
		)
		(stroke
			(width 0)
			(type default)
		)
	)
	(wire
		(pts
			(xy 266.7 149.86) (xy 276.86 149.86)
		)
		(stroke
			(width 0)
			(type default)
		)
	)
	(wire
		(pts
			(xy 247.65 147.32) (xy 247.65 142.24)
		)
		(stroke
			(width 0)
			(type default)
		)
	)
	(wire
		(pts
			(xy 91.44 172.72) (xy 91.44 154.94)
		)
		(stroke
			(width 0)
			(type default)
		)
	)
	(wire
		(pts
			(xy 91.44 120.65) (xy 91.44 142.24)
		)
		(stroke
			(width 0)
			(type default)
		)
	)
	(wire
		(pts
			(xy 314.96 240.03) (xy 314.96 205.74)
		)
		(stroke
			(width 0)
			(type default)
		)
	)
	(wire
		(pts
			(xy 83.82 85.09) (xy 96.52 85.09)
		)
		(stroke
			(width 0)
			(type default)
		)
	)
	(wire
		(pts
			(xy 364.49 63.5) (xy 374.65 63.5)
		)
		(stroke
			(width 0)
			(type default)
		)
	)
	(wire
		(pts
			(xy 217.17 63.5) (xy 217.17 71.12)
		)
		(stroke
			(width 0)
			(type default)
		)
	)
	(wire
		(pts
			(xy 349.25 228.6) (xy 346.71 228.6)
		)
		(stroke
			(width 0)
			(type default)
		)
	)
	(wire
		(pts
			(xy 41.91 87.63) (xy 44.45 87.63)
		)
		(stroke
			(width 0)
			(type default)
		)
	)
	(wire
		(pts
			(xy 217.17 175.26) (xy 217.17 177.8)
		)
		(stroke
			(width 0)
			(type default)
		)
	)
	(wire
		(pts
			(xy 332.74 101.6) (xy 344.17 101.6)
		)
		(stroke
			(width 0)
			(type default)
		)
	)
	(wire
		(pts
			(xy 332.74 156.21) (xy 332.74 157.48)
		)
		(stroke
			(width 0)
			(type default)
		)
	)
	(wire
		(pts
			(xy 391.16 22.86) (xy 391.16 25.4)
		)
		(stroke
			(width 0)
			(type default)
		)
	)
	(wire
		(pts
			(xy 294.64 25.4) (xy 307.34 25.4)
		)
		(stroke
			(width 0)
			(type default)
		)
	)
	(wire
		(pts
			(xy 391.16 137.16) (xy 391.16 139.7)
		)
		(stroke
			(width 0)
			(type default)
		)
	)
	(wire
		(pts
			(xy 260.35 238.76) (xy 271.78 238.76)
		)
		(stroke
			(width 0)
			(type default)
		)
	)
	(wire
		(pts
			(xy 41.91 90.17) (xy 44.45 90.17)
		)
		(stroke
			(width 0)
			(type default)
		)
	)
	(wire
		(pts
			(xy 247.65 195.58) (xy 247.65 190.5)
		)
		(stroke
			(width 0)
			(type default)
		)
	)
	(wire
		(pts
			(xy 391.16 175.26) (xy 391.16 177.8)
		)
		(stroke
			(width 0)
			(type default)
		)
	)
	(wire
		(pts
			(xy 237.49 101.6) (xy 276.86 101.6)
		)
		(stroke
			(width 0)
			(type default)
		)
	)
	(wire
		(pts
			(xy 217.17 63.5) (xy 227.33 63.5)
		)
		(stroke
			(width 0)
			(type default)
		)
	)
	(wire
		(pts
			(xy 374.65 139.7) (xy 374.65 147.32)
		)
		(stroke
			(width 0)
			(type default)
		)
	)
	(wire
		(pts
			(xy 344.17 119.38) (xy 344.17 114.3)
		)
		(stroke
			(width 0)
			(type default)
		)
	)
	(wire
		(pts
			(xy 297.18 40.64) (xy 294.64 40.64)
		)
		(stroke
			(width 0)
			(type default)
		)
	)
	(wire
		(pts
			(xy 364.49 43.18) (xy 364.49 38.1)
		)
		(stroke
			(width 0)
			(type default)
		)
	)
	(wire
		(pts
			(xy 254 233.68) (xy 254 231.14)
		)
		(stroke
			(width 0)
			(type default)
		)
	)
	(wire
		(pts
			(xy 237.49 63.5) (xy 237.49 71.12)
		)
		(stroke
			(width 0)
			(type default)
		)
	)
	(wire
		(pts
			(xy 354.33 119.38) (xy 354.33 114.3)
		)
		(stroke
			(width 0)
			(type default)
		)
	)
	(wire
		(pts
			(xy 203.2 233.68) (xy 203.2 231.14)
		)
		(stroke
			(width 0)
			(type default)
		)
	)
	(wire
		(pts
			(xy 304.8 213.36) (xy 304.8 215.9)
		)
		(stroke
			(width 0)
			(type default)
		)
	)
	(wire
		(pts
			(xy 346.71 228.6) (xy 346.71 231.14)
		)
		(stroke
			(width 0)
			(type default)
		)
	)
	(wire
		(pts
			(xy 227.33 81.28) (xy 227.33 76.2)
		)
		(stroke
			(width 0)
			(type default)
		)
	)
	(wire
		(pts
			(xy 374.65 139.7) (xy 379.73 139.7)
		)
		(stroke
			(width 0)
			(type default)
		)
	)
	(wire
		(pts
			(xy 344.17 101.6) (xy 350.52 101.6)
		)
		(stroke
			(width 0)
			(type default)
		)
	)
	(wire
		(pts
			(xy 143.51 85.09) (xy 143.51 120.65)
		)
		(stroke
			(width 0)
			(type default)
		)
	)
	(wire
		(pts
			(xy 344.17 81.28) (xy 344.17 76.2)
		)
		(stroke
			(width 0)
			(type default)
		)
	)
	(wire
		(pts
			(xy 177.8 231.14) (xy 177.8 246.38)
		)
		(stroke
			(width 0)
			(type default)
		)
	)
	(wire
		(pts
			(xy 256.54 154.94) (xy 259.08 154.94)
		)
		(stroke
			(width 0)
			(type default)
		)
	)
	(wire
		(pts
			(xy 391.16 177.8) (xy 400.05 177.8)
		)
		(stroke
			(width 0)
			(type default)
		)
	)
	(wire
		(pts
			(xy 83.82 92.71) (xy 83.82 95.25)
		)
		(stroke
			(width 0)
			(type default)
		)
	)
	(wire
		(pts
			(xy 391.16 60.96) (xy 391.16 63.5)
		)
		(stroke
			(width 0)
			(type default)
		)
	)
	(wire
		(pts
			(xy 312.42 240.03) (xy 314.96 240.03)
		)
		(stroke
			(width 0)
			(type default)
		)
	)
	(wire
		(pts
			(xy 259.08 154.94) (xy 259.08 187.96)
		)
		(stroke
			(width 0)
			(type default)
		)
	)
	(wire
		(pts
			(xy 374.65 101.6) (xy 379.73 101.6)
		)
		(stroke
			(width 0)
			(type default)
		)
	)
	(wire
		(pts
			(xy 64.77 85.09) (xy 74.93 85.09)
		)
		(stroke
			(width 0)
			(type default)
		)
	)
	(wire
		(pts
			(xy 294.64 149.86) (xy 327.66 149.86)
		)
		(stroke
			(width 0)
			(type default)
		)
	)
	(wire
		(pts
			(xy 297.18 43.18) (xy 297.18 40.64)
		)
		(stroke
			(width 0)
			(type default)
		)
	)
	(wire
		(pts
			(xy 400.05 177.8) (xy 400.05 175.26)
		)
		(stroke
			(width 0)
			(type default)
		)
	)
	(wire
		(pts
			(xy 83.82 100.33) (xy 83.82 102.87)
		)
		(stroke
			(width 0)
			(type default)
		)
	)
	(wire
		(pts
			(xy 58.42 102.87) (xy 58.42 96.52)
		)
		(stroke
			(width 0)
			(type default)
		)
	)
	(wire
		(pts
			(xy 297.18 81.28) (xy 297.18 78.74)
		)
		(stroke
			(width 0)
			(type default)
		)
	)
	(wire
		(pts
			(xy 279.4 243.84) (xy 279.4 246.38)
		)
		(stroke
			(width 0)
			(type default)
		)
	)
	(wire
		(pts
			(xy 228.6 233.68) (xy 228.6 231.14)
		)
		(stroke
			(width 0)
			(type default)
		)
	)
	(wire
		(pts
			(xy 256.54 38.1) (xy 256.54 40.64)
		)
		(stroke
			(width 0)
			(type default)
		)
	)
	(wire
		(pts
			(xy 247.65 109.22) (xy 247.65 104.14)
		)
		(stroke
			(width 0)
			(type default)
		)
	)
	(wire
		(pts
			(xy 384.81 63.5) (xy 391.16 63.5)
		)
		(stroke
			(width 0)
			(type default)
		)
	)
	(wire
		(pts
			(xy 227.33 63.5) (xy 237.49 63.5)
		)
		(stroke
			(width 0)
			(type default)
		)
	)
	(wire
		(pts
			(xy 101.6 170.18) (xy 101.6 172.72)
		)
		(stroke
			(width 0)
			(type default)
		)
	)
	(wire
		(pts
			(xy 327.66 187.96) (xy 332.74 187.96)
		)
		(stroke
			(width 0)
			(type default)
		)
	)
	(wire
		(pts
			(xy 48.26 170.18) (xy 53.34 170.18)
		)
		(stroke
			(width 0)
			(type default)
		)
	)
	(wire
		(pts
			(xy 332.74 101.6) (xy 332.74 104.14)
		)
		(stroke
			(width 0)
			(type default)
		)
	)
	(wire
		(pts
			(xy 304.8 243.84) (xy 304.8 246.38)
		)
		(stroke
			(width 0)
			(type default)
		)
	)
	(wire
		(pts
			(xy 237.49 177.8) (xy 276.86 177.8)
		)
		(stroke
			(width 0)
			(type default)
		)
	)
	(wire
		(pts
			(xy 344.17 177.8) (xy 344.17 185.42)
		)
		(stroke
			(width 0)
			(type default)
		)
	)
	(wire
		(pts
			(xy 344.17 177.8) (xy 350.52 177.8)
		)
		(stroke
			(width 0)
			(type default)
		)
	)
	(wire
		(pts
			(xy 374.65 43.18) (xy 374.65 38.1)
		)
		(stroke
			(width 0)
			(type default)
		)
	)
	(wire
		(pts
			(xy 374.65 195.58) (xy 374.65 190.5)
		)
		(stroke
			(width 0)
			(type default)
		)
	)
	(wire
		(pts
			(xy 227.33 25.4) (xy 227.33 33.02)
		)
		(stroke
			(width 0)
			(type default)
		)
	)
	(wire
		(pts
			(xy 332.74 101.6) (xy 327.66 101.6)
		)
		(stroke
			(width 0)
			(type default)
		)
	)
	(wire
		(pts
			(xy 327.66 35.56) (xy 332.74 35.56)
		)
		(stroke
			(width 0)
			(type default)
		)
	)
	(wire
		(pts
			(xy 332.74 139.7) (xy 344.17 139.7)
		)
		(stroke
			(width 0)
			(type default)
		)
	)
	(table
		(column_count 1)
		(border
			(external yes)
			(header yes)
			(stroke
				(width 0)
				(type solid)
			)
		)
		(separators
			(rows yes)
			(cols yes)
			(stroke
				(width 0)
				(type solid)
			)
		)
		(column_widths 22.86)
		(row_heights 3.81 6.35)
		(cells
			(table_cell "Requirements"
				(exclude_from_sim no)
				(at 161.29 58.42 0)
				(size 22.86 3.81)
				(margins 0.9525 0.9525 0.9525 0.9525)
				(span 1 1)
				(fill
					(type none)
				)
				(effects
					(font
						(size 1.27 1.27)
					)
				)
			)
			(table_cell "0.87-0.96V\nMax ripple: 20mV_{p-p}"
				(exclude_from_sim no)
				(at 161.29 62.23 0)
				(size 22.86 6.35)
				(margins 0.9525 0.9525 0.9525 0.9525)
				(span 1 1)
				(fill
					(type none)
				)
				(effects
					(font
						(size 1.27 1.27)
					)
				)
			)
		)
	)
	(table
		(column_count 1)
		(border
			(external yes)
			(header yes)
			(stroke
				(width 0)
				(type solid)
			)
		)
		(separators
			(rows yes)
			(cols yes)
			(stroke
				(width 0)
				(type solid)
			)
		)
		(column_widths 22.86)
		(row_heights 3.81 6.35)
		(cells
			(table_cell "Requirements"
				(exclude_from_sim no)
				(at 161.29 134.62 0)
				(size 22.86 3.81)
				(margins 0.9525 0.9525 0.9525 0.9525)
				(span 1 1)
				(fill
					(type none)
				)
				(effects
					(font
						(size 1.27 1.27)
					)
				)
			)
			(table_cell "0.95-1.05V\nMax ripple: 10mV_{p-p}"
				(exclude_from_sim no)
				(at 161.29 138.43 0)
				(size 22.86 6.35)
				(margins 0.9525 0.9525 0.9525 0.9525)
				(span 1 1)
				(fill
					(type none)
				)
				(effects
					(font
						(size 1.27 1.27)
					)
				)
			)
		)
	)
	(table
		(column_count 1)
		(border
			(external yes)
			(header yes)
			(stroke
				(width 0)
				(type solid)
			)
		)
		(separators
			(rows yes)
			(cols yes)
			(stroke
				(width 0)
				(type solid)
			)
		)
		(column_widths 66.04)
		(row_heights 2.54 5.08)
		(cells
			(table_cell "POWER SEQUENCING"
				(exclude_from_sim no)
				(at 207.01 13.97 0)
				(size 66.04 2.54)
				(margins 0.9525 0.9525 0.9525 0.9525)
				(span 1 1)
				(fill
					(type none)
				)
				(effects
					(font
						(size 1.27 1.27)
					)
				)
			)
			(table_cell ""
				(exclude_from_sim no)
				(at 207.01 16.51 0)
				(size 66.04 5.08)
				(margins 0.9525 0.9525 0.9525 0.9525)
				(span 1 1)
				(fill
					(type none)
				)
				(effects
					(font
						(size 1.27 1.27)
					)
					(justify left top)
				)
			)
		)
	)
	(table
		(column_count 1)
		(border
			(external yes)
			(header yes)
			(stroke
				(width 0)
				(type solid)
			)
		)
		(separators
			(rows yes)
			(cols yes)
			(stroke
				(width 0)
				(type solid)
			)
		)
		(column_widths 22.86)
		(row_heights 3.81 6.35)
		(cells
			(table_cell "Requirements"
				(exclude_from_sim no)
				(at 161.29 96.52 0)
				(size 22.86 3.81)
				(margins 0.9525 0.9525 0.9525 0.9525)
				(span 1 1)
				(fill
					(type none)
				)
				(effects
					(font
						(size 1.27 1.27)
					)
				)
			)
			(table_cell "1.8236-1.9364V\nMax ripple: 50mV_{p-p}"
				(exclude_from_sim no)
				(at 161.29 100.33 0)
				(size 22.86 6.35)
				(margins 0.9525 0.9525 0.9525 0.9525)
				(span 1 1)
				(fill
					(type none)
				)
				(effects
					(font
						(size 1.27 1.27)
					)
				)
			)
		)
	)
	(table
		(column_count 1)
		(border
			(external yes)
			(header yes)
			(stroke
				(width 0)
				(type solid)
			)
		)
		(separators
			(rows yes)
			(cols yes)
			(stroke
				(width 0)
				(type solid)
			)
		)
		(column_widths 22.86)
		(row_heights 3.81 6.35)
		(cells
			(table_cell "Requirements"
				(exclude_from_sim no)
				(at 161.29 20.32 0)
				(size 22.86 3.81)
				(margins 0.9525 0.9525 0.9525 0.9525)
				(span 1 1)
				(fill
					(type none)
				)
				(effects
					(font
						(size 1.27 1.27)
					)
				)
			)
			(table_cell "3.14-3.47V\nMax ripple: 70mV_{p-p}"
				(exclude_from_sim no)
				(at 161.29 24.13 0)
				(size 22.86 6.35)
				(margins 0.9525 0.9525 0.9525 0.9525)
				(span 1 1)
				(fill
					(type none)
				)
				(effects
					(font
						(size 1.27 1.27)
					)
				)
			)
		)
	)
	(table
		(column_count 1)
		(border
			(external yes)
			(header yes)
			(stroke
				(width 0)
				(type solid)
			)
		)
		(separators
			(rows yes)
			(cols yes)
			(stroke
				(width 0)
				(type solid)
			)
		)
		(column_widths 22.86)
		(row_heights 3.81 6.35)
		(cells
			(table_cell "Requirements"
				(exclude_from_sim no)
				(at 161.29 172.72 0)
				(size 22.86 3.81)
				(margins 0.9525 0.9525 0.9525 0.9525)
				(span 1 1)
				(fill
					(type none)
				)
				(effects
					(font
						(size 1.27 1.27)
					)
				)
			)
			(table_cell "0.95-1.05V\nMax ripple: 30mV_{p-p}"
				(exclude_from_sim no)
				(at 161.29 176.53 0)
				(size 22.86 6.35)
				(margins 0.9525 0.9525 0.9525 0.9525)
				(span 1 1)
				(fill
					(type none)
				)
				(effects
					(font
						(size 1.27 1.27)
					)
				)
			)
		)
	)
	(label "VCCD_SW"
		(at 294.64 63.5 0)
		(effects
			(font
				(size 1.27 1.27)
			)
			(justify left bottom)
		)
	)
	(label "+5V_USB"
		(at 52.07 120.65 0)
		(effects
			(font
				(size 1.27 1.27)
			)
			(justify left bottom)
		)
	)
	(label "1V0_BST"
		(at 294.64 144.78 0)
		(effects
			(font
				(size 1.27 1.27)
			)
			(justify left bottom)
		)
	)
	(label "+3V3_OUT"
		(at 166.37 215.9 0)
		(effects
			(font
				(size 1.27 1.27)
			)
			(justify left bottom)
		)
	)
	(label "CC1"
		(at 52.07 125.73 0)
		(effects
			(font
				(size 1.27 1.27)
			)
			(justify left bottom)
		)
	)
	(label "DVDD_EN"
		(at 276.86 187.96 180)
		(effects
			(font
				(size 1.27 1.27)
			)
			(justify right bottom)
		)
	)
	(label "+DVDD_OUT"
		(at 344.17 177.8 180)
		(effects
			(font
				(size 1.27 1.27)
			)
			(justify right bottom)
		)
	)
	(label "1V0_FB"
		(at 294.64 149.86 0)
		(effects
			(font
				(size 1.27 1.27)
			)
			(justify left bottom)
		)
	)
	(label "1V88_SW"
		(at 294.64 101.6 0)
		(effects
			(font
				(size 1.27 1.27)
			)
			(justify left bottom)
		)
	)
	(label "VCCD_VCC"
		(at 276.86 66.04 180)
		(effects
			(font
				(size 1.27 1.27)
			)
			(justify right bottom)
		)
	)
	(label "3V3_EN"
		(at 207.01 34.29 180)
		(effects
			(font
				(size 1.27 1.27)
			)
			(justify right bottom)
		)
	)
	(label "3V3_BST"
		(at 294.64 30.48 0)
		(effects
			(font
				(size 1.27 1.27)
			)
			(justify left bottom)
		)
	)
	(label "1V88_BST"
		(at 294.64 106.68 0)
		(effects
			(font
				(size 1.27 1.27)
			)
			(justify left bottom)
		)
	)
	(label "3V3_VCC"
		(at 276.86 27.94 180)
		(effects
			(font
				(size 1.27 1.27)
			)
			(justify right bottom)
		)
	)
	(label "DVDD_FB"
		(at 294.64 187.96 0)
		(effects
			(font
				(size 1.27 1.27)
			)
			(justify left bottom)
		)
	)
	(label "+1V0_OUT"
		(at 234.95 238.76 0)
		(effects
			(font
				(size 1.27 1.27)
			)
			(justify left bottom)
		)
	)
	(label "1V88_EN"
		(at 276.86 111.76 180)
		(effects
			(font
				(size 1.27 1.27)
			)
			(justify right bottom)
		)
	)
	(label "+VCCD_OUT"
		(at 184.15 238.76 0)
		(effects
			(font
				(size 1.27 1.27)
			)
			(justify left bottom)
		)
	)
	(label "1V0_VCC"
		(at 276.86 142.24 180)
		(effects
			(font
				(size 1.27 1.27)
			)
			(justify right bottom)
		)
	)
	(label "+VCCD_OUT"
		(at 344.17 63.5 180)
		(effects
			(font
				(size 1.27 1.27)
			)
			(justify right bottom)
		)
	)
	(label "DVDD_PG"
		(at 276.86 193.04 180)
		(effects
			(font
				(size 1.27 1.27)
			)
			(justify right bottom)
		)
	)
	(label "DVDD_SW"
		(at 294.64 177.8 0)
		(effects
			(font
				(size 1.27 1.27)
			)
			(justify left bottom)
		)
	)
	(label "1V0_PG"
		(at 276.86 154.94 180)
		(effects
			(font
				(size 1.27 1.27)
			)
			(justify right bottom)
		)
	)
	(label "+12V_IN"
		(at 379.73 220.98 0)
		(effects
			(font
				(size 1.27 1.27)
			)
			(justify left bottom)
		)
	)
	(label "+3V3_OUT"
		(at 344.17 25.4 180)
		(effects
			(font
				(size 1.27 1.27)
			)
			(justify right bottom)
		)
	)
	(label "+1V0_OUT"
		(at 344.17 139.7 180)
		(effects
			(font
				(size 1.27 1.27)
			)
			(justify right bottom)
		)
	)
	(label "DVDD_VCC"
		(at 276.86 180.34 180)
		(effects
			(font
				(size 1.27 1.27)
			)
			(justify right bottom)
		)
	)
	(label "1V88_VCC"
		(at 276.86 104.14 180)
		(effects
			(font
				(size 1.27 1.27)
			)
			(justify right bottom)
		)
	)
	(label "+1V88_OUT"
		(at 209.55 238.76 0)
		(effects
			(font
				(size 1.27 1.27)
			)
			(justify left bottom)
		)
	)
	(label "VCCD_BST"
		(at 294.64 68.58 0)
		(effects
			(font
				(size 1.27 1.27)
			)
			(justify left bottom)
		)
	)
	(label "+5V_USB"
		(at 379.73 223.52 0)
		(effects
			(font
				(size 1.27 1.27)
			)
			(justify left bottom)
		)
	)
	(label "1V0_SW"
		(at 294.64 139.7 0)
		(effects
			(font
				(size 1.27 1.27)
			)
			(justify left bottom)
		)
	)
	(label "3V3_FB"
		(at 294.64 35.56 0)
		(effects
			(font
				(size 1.27 1.27)
			)
			(justify left bottom)
		)
	)
	(label "DVDD_BST"
		(at 294.64 182.88 0)
		(effects
			(font
				(size 1.27 1.27)
			)
			(justify left bottom)
		)
	)
	(label "ALL_RAILS_OK"
		(at 323.85 240.03 0)
		(effects
			(font
				(size 1.27 1.27)
			)
			(justify left bottom)
		)
	)
	(label "3V3_EN"
		(at 269.24 35.56 0)
		(effects
			(font
				(size 1.27 1.27)
			)
			(justify left bottom)
		)
	)
	(label "VCCD_FB"
		(at 294.64 73.66 0)
		(effects
			(font
				(size 1.27 1.27)
			)
			(justify left bottom)
		)
	)
	(label "1V88_FB"
		(at 294.64 111.76 0)
		(effects
			(font
				(size 1.27 1.27)
			)
			(justify left bottom)
		)
	)
	(label "3V3_PG"
		(at 276.86 40.64 180)
		(effects
			(font
				(size 1.27 1.27)
			)
			(justify right bottom)
		)
	)
	(label "3V3_SW"
		(at 294.64 25.4 0)
		(effects
			(font
				(size 1.27 1.27)
			)
			(justify left bottom)
		)
	)
	(label "1V88_PG"
		(at 276.86 116.84 180)
		(effects
			(font
				(size 1.27 1.27)
			)
			(justify right bottom)
		)
	)
	(label "VCCD_EN"
		(at 276.86 73.66 180)
		(effects
			(font
				(size 1.27 1.27)
			)
			(justify right bottom)
		)
	)
	(label "CC2"
		(at 52.07 128.27 0)
		(effects
			(font
				(size 1.27 1.27)
			)
			(justify left bottom)
		)
	)
	(label "+1V88_OUT"
		(at 344.17 101.6 180)
		(effects
			(font
				(size 1.27 1.27)
			)
			(justify right bottom)
		)
	)
	(label "+DVDD_OUT"
		(at 260.35 238.76 0)
		(effects
			(font
				(size 1.27 1.27)
			)
			(justify left bottom)
		)
	)
	(label "VCCD_PG"
		(at 276.86 78.74 180)
		(effects
			(font
				(size 1.27 1.27)
			)
			(justify right bottom)
		)
	)
	(label "+12V_IN"
		(at 44.45 85.09 0)
		(effects
			(font
				(size 1.27 1.27)
			)
			(justify left bottom)
		)
	)
	(label "1V0_EN"
		(at 276.86 149.86 180)
		(effects
			(font
				(size 1.27 1.27)
			)
			(justify right bottom)
		)
	)
	(hierarchical_label "~{CPRSNT}"
		(shape output)
		(at 349.25 228.6 0)
		(effects
			(font
				(size 1.27 1.27)
			)
			(justify left)
		)
	)
	(netclass_flag ""
		(length 2.54)
		(shape round)
		(at 124.46 83.82 0)
		(effects
			(font
				(size 1.27 1.27)
			)
			(justify left bottom)
		)
		(property "Netclass" "PWR"
			(at 124.46 78.74 0)
			(effects
				(font
					(size 1.27 1.27)
				)
			)
		)
		(property "Component Class" ""
			(at -99.06 30.48 0)
			(effects
				(font
					(size 1.27 1.27)
					(italic yes)
				)
				(justify right)
			)
		)
	)
	(symbol
		(lib_id "antmicroResistors0402:R_0R_0402")
		(at 261.62 187.96 0)
		(unit 1)
		(exclude_from_sim no)
		(in_bom yes)
		(on_board yes)
		(dnp no)
		(property "Reference" "R30"
			(at 264.16 185.674 0)
			(effects
				(font
					(size 1.27 1.27)
					(thickness 0.15)
				)
			)
		)
		(property "Value" "R_0R_0402"
			(at 281.94 200.66 0)
			(effects
				(font
					(size 1.27 1.27)
					(thickness 0.15)
				)
				(justify left bottom)
				(hide yes)
			)
		)
		(property "Footprint" "antmicro-footprints:R_0402_1005Metric"
			(at 281.94 203.2 0)
			(effects
				(font
					(size 1.27 1.27)
					(thickness 0.15)
				)
				(justify left bottom)
				(hide yes)
			)
		)
		(property "Datasheet" "https://industrial.panasonic.com/cdbs/www-data/pdf/RDA0000/AOA0000C301.pdf"
			(at 281.94 205.74 0)
			(effects
				(font
					(size 1.27 1.27)
					(thickness 0.15)
				)
				(justify left bottom)
				(hide yes)
			)
		)
		(property "Description" "SMD Chip Resistor, Jumper, 0 ohm, 100 mW, 0402 [1005 Metric], Thick Film, General Purpose"
			(at 281.94 220.98 0)
			(effects
				(font
					(size 1.27 1.27)
				)
				(justify left bottom)
				(hide yes)
			)
		)
		(property "MPN" "ERJ2GE0R00X"
			(at 281.94 208.28 0)
			(effects
				(font
					(size 1.27 1.27)
					(thickness 0.15)
				)
				(justify left bottom)
				(hide yes)
			)
		)
		(property "Manufacturer" "Panasonic"
			(at 281.94 210.82 0)
			(effects
				(font
					(size 1.27 1.27)
					(thickness 0.15)
				)
				(justify left bottom)
				(hide yes)
			)
		)
		(property "License" "Apache-2.0"
			(at 281.94 213.36 0)
			(effects
				(font
					(size 1.27 1.27)
					(thickness 0.15)
				)
				(justify left bottom)
				(hide yes)
			)
		)
		(property "Author" "Antmicro"
			(at 281.94 215.9 0)
			(effects
				(font
					(size 1.27 1.27)
					(thickness 0.15)
				)
				(justify left bottom)
				(hide yes)
			)
		)
		(property "Val" "0R"
			(at 264.16 190.246 0)
			(effects
				(font
					(size 1.27 1.27)
					(thickness 0.15)
				)
			)
		)
		(property "Tolerance" "~"
			(at 281.94 198.12 0)
			(effects
				(font
					(size 1.27 1.27)
				)
				(justify left bottom)
				(hide yes)
			)
		)
		(property "Current" "1A"
			(at 281.94 218.44 0)
			(effects
				(font
					(size 1.27 1.27)
					(thickness 0.15)
				)
				(justify left bottom)
				(hide yes)
			)
		)
		(pin "2"
		)
		(pin "1"
		)
		(instances
			(project "OCuLink to 10GbE adapter"
				(path ""
					(reference "R30")
					(unit 1)
				)
			)
		)
	)
	(symbol
		(lib_id "antmicroCapacitors0603:C_22u_16V_0603")
		(at 364.49 190.5 90)
		(unit 1)
		(exclude_from_sim no)
		(in_bom yes)
		(on_board yes)
		(dnp no)
		(property "Reference" "C208"
			(at 366.268 186.69 90)
			(effects
				(font
					(size 1.27 1.27)
					(thickness 0.15)
				)
				(justify right)
			)
		)
		(property "Value" "C_22u_16V_0603"
			(at 374.65 170.18 0)
			(effects
				(font
					(size 1.27 1.27)
					(thickness 0.15)
				)
				(justify left bottom)
				(hide yes)
			)
		)
		(property "Footprint" "antmicro-footprints:C_0603_1608Metric_EIA"
			(at 377.19 170.18 0)
			(effects
				(font
					(size 1.27 1.27)
					(thickness 0.15)
				)
				(justify left bottom)
				(hide yes)
			)
		)
		(property "Datasheet" "https://product.samsungsem.com/mlcc/CL10A226MO7JZN.do"
			(at 379.73 170.18 0)
			(effects
				(font
					(size 1.27 1.27)
					(thickness 0.15)
				)
				(justify left bottom)
				(hide yes)
			)
		)
		(property "Description" "SMD Multilayer Ceramic Capacitor"
			(at 364.49 190.5 0)
			(effects
				(font
					(size 1.27 1.27)
				)
				(hide yes)
			)
		)
		(property "MPN" "CL10A226MO7JZNC"
			(at 382.27 170.18 0)
			(effects
				(font
					(size 1.27 1.27)
					(thickness 0.15)
				)
				(justify left bottom)
				(hide yes)
			)
		)
		(property "Manufacturer" "Samsung Electro-Mechanics"
			(at 384.81 170.18 0)
			(effects
				(font
					(size 1.27 1.27)
					(thickness 0.15)
				)
				(justify left bottom)
				(hide yes)
			)
		)
		(property "License" "Apache-2.0"
			(at 387.35 170.18 0)
			(effects
				(font
					(size 1.27 1.27)
					(thickness 0.15)
				)
				(justify left bottom)
				(hide yes)
			)
		)
		(property "Author" "Antmicro"
			(at 389.89 170.18 0)
			(effects
				(font
					(size 1.27 1.27)
					(thickness 0.15)
				)
				(justify left bottom)
				(hide yes)
			)
		)
		(property "Val" "22u"
			(at 366.268 189.23 90)
			(effects
				(font
					(size 1.27 1.27)
					(thickness 0.15)
				)
				(justify right)
			)
		)
		(property "Voltage" "16V"
			(at 367.03 190.4935 90)
			(effects
				(font
					(size 1.27 1.27)
				)
				(justify right)
				(hide yes)
			)
		)
		(property "Dielectric" ""
			(at 394.97 170.18 0)
			(effects
				(font
					(size 1.27 1.27)
				)
				(justify left bottom)
				(hide yes)
			)
		)
		(property "Public" "False"
			(at 397.51 170.18 0)
			(effects
				(font
					(size 1.27 1.27)
				)
				(justify left bottom)
				(hide yes)
			)
		)
		(pin "2"
		)
		(pin "1"
		)
		(instances
			(project "OCuLink to 10GbE adapter"
				(path ""
					(reference "C208")
					(unit 1)
				)
			)
		)
	)
	(symbol
		(lib_id "antmicroCapacitors0402:C_1u_25V_0402")
		(at 247.65 152.4 270)
		(mirror x)
		(unit 1)
		(exclude_from_sim no)
		(in_bom yes)
		(on_board yes)
		(dnp no)
		(property "Reference" "C33"
			(at 245.872 148.59 90)
			(effects
				(font
					(size 1.27 1.27)
					(thickness 0.15)
				)
				(justify right)
			)
		)
		(property "Value" "C_1u_25V_0402"
			(at 237.49 132.08 0)
			(effects
				(font
					(size 1.27 1.27)
					(thickness 0.15)
				)
				(justify left bottom)
				(hide yes)
			)
		)
		(property "Footprint" "antmicro-footprints:C_0402_1005Metric"
			(at 234.95 132.08 0)
			(effects
				(font
					(size 1.27 1.27)
					(thickness 0.15)
				)
				(justify left bottom)
				(hide yes)
			)
		)
		(property "Datasheet" "https://www.murata.com/products/productdetail?partno=GRM155R61E105KE11%23"
			(at 232.41 132.08 0)
			(effects
				(font
					(size 1.27 1.27)
					(thickness 0.15)
				)
				(justify left bottom)
				(hide yes)
			)
		)
		(property "Description" "SMD Multilayer Ceramic Capacitor, 1 µF, 25 V, 0402 [1005 Metric], ± 10%, X5R, GRM Series"
			(at 214.63 132.08 0)
			(effects
				(font
					(size 1.27 1.27)
				)
				(justify left bottom)
				(hide yes)
			)
		)
		(property "MPN" "GRM155R61E105KE11J"
			(at 229.87 132.08 0)
			(effects
				(font
					(size 1.27 1.27)
					(thickness 0.15)
				)
				(justify left bottom)
				(hide yes)
			)
		)
		(property "Manufacturer" "Murata"
			(at 227.33 132.08 0)
			(effects
				(font
					(size 1.27 1.27)
					(thickness 0.15)
				)
				(justify left bottom)
				(hide yes)
			)
		)
		(property "License" "Apache-2.0"
			(at 224.79 132.08 0)
			(effects
				(font
					(size 1.27 1.27)
					(thickness 0.15)
				)
				(justify left bottom)
				(hide yes)
			)
		)
		(property "Author" "Antmicro"
			(at 222.25 132.08 0)
			(effects
				(font
					(size 1.27 1.27)
					(thickness 0.15)
				)
				(justify left bottom)
				(hide yes)
			)
		)
		(property "Val" "1u"
			(at 245.872 151.13 90)
			(effects
				(font
					(size 1.27 1.27)
					(thickness 0.15)
				)
				(justify right)
			)
		)
		(property "Voltage" "25V"
			(at 219.71 132.08 0)
			(effects
				(font
					(size 1.27 1.27)
				)
				(justify left bottom)
				(hide yes)
			)
		)
		(property "Dielectric" "X5R"
			(at 217.17 132.08 0)
			(effects
				(font
					(size 1.27 1.27)
				)
				(justify left bottom)
				(hide yes)
			)
		)
		(pin "2"
		)
		(pin "1"
		)
		(instances
			(project "OCuLink to 10GbE adapter"
				(path ""
					(reference "C33")
					(unit 1)
				)
			)
		)
	)
	(symbol
		(lib_id "antmicroLEDIndicationDiscrete:LED_G_0603_LG_L29K-G2J1-24-Z")
		(at 83.82 100.33 90)
		(unit 1)
		(exclude_from_sim no)
		(in_bom yes)
		(on_board yes)
		(dnp no)
		(property "Reference" "D2"
			(at 85.09 96.52 90)
			(effects
				(font
					(size 1.27 1.27)
					(thickness 0.15)
				)
				(justify right)
			)
		)
		(property "Value" "LED_G_0603_LG_L29K-G2J1-24-Z"
			(at 91.44 80.01 0)
			(effects
				(font
					(size 1.27 1.27)
					(thickness 0.15)
				)
				(justify left bottom)
				(hide yes)
			)
		)
		(property "Footprint" "antmicro-footprints:LED_0603_1608Metric_G"
			(at 93.98 80.01 0)
			(effects
				(font
					(size 1.27 1.27)
					(thickness 0.15)
				)
				(justify left bottom)
				(hide yes)
			)
		)
		(property "Datasheet" "https://look.ams-osram.com/m/19ee86b3ae0ee95b/original/LG-L29K.pdf"
			(at 96.52 80.01 0)
			(effects
				(font
					(size 1.27 1.27)
					(thickness 0.15)
				)
				(justify left bottom)
				(hide yes)
			)
		)
		(property "Description" "LED, Green, SMD, 0603, 20 mA, 1.7 V, 570 nm"
			(at 83.82 100.33 0)
			(effects
				(font
					(size 1.27 1.27)
				)
				(hide yes)
			)
		)
		(property "MPN" "LG L29K-G2J1-24-Z"
			(at 99.06 80.01 0)
			(effects
				(font
					(size 1.27 1.27)
					(thickness 0.15)
				)
				(justify left bottom)
				(hide yes)
			)
		)
		(property "Manufacturer" "OSRAM"
			(at 101.6 80.01 0)
			(effects
				(font
					(size 1.27 1.27)
					(thickness 0.15)
				)
				(justify left bottom)
				(hide yes)
			)
		)
		(property "Color" "Green"
			(at 85.09 99.0599 90)
			(effects
				(font
					(size 1.27 1.27)
				)
				(justify right)
			)
		)
		(property "Author" "Antmicro"
			(at 104.14 80.01 0)
			(effects
				(font
					(size 1.27 1.27)
					(thickness 0.15)
				)
				(justify left bottom)
				(hide yes)
			)
		)
		(property "License" "Apache-2.0"
			(at 106.68 80.01 0)
			(effects
				(font
					(size 1.27 1.27)
					(thickness 0.15)
				)
				(justify left bottom)
				(hide yes)
			)
		)
		(pin "2"
		)
		(pin "1"
		)
		(instances
			(project "OCuLink to 10GbE adapter"
				(path ""
					(reference "D2")
					(unit 1)
				)
			)
		)
	)
	(symbol
		(lib_id "antmicropower:GND")
		(at 227.33 119.38 0)
		(unit 1)
		(exclude_from_sim no)
		(in_bom yes)
		(on_board yes)
		(dnp no)
		(property "Reference" "#PWR028"
			(at 236.22 121.92 0)
			(effects
				(font
					(size 1.27 1.27)
					(thickness 0.15)
				)
				(justify left bottom)
				(hide yes)
			)
		)
		(property "Value" "GND"
			(at 227.33 123.19 0)
			(effects
				(font
					(size 1.27 1.27)
					(thickness 0.15)
				)
			)
		)
		(property "Footprint" ""
			(at 236.22 127 0)
			(effects
				(font
					(size 1.27 1.27)
					(thickness 0.15)
				)
				(justify left bottom)
				(hide yes)
			)
		)
		(property "Datasheet" ""
			(at 236.22 132.08 0)
			(effects
				(font
					(size 1.27 1.27)
					(thickness 0.15)
				)
				(justify left bottom)
				(hide yes)
			)
		)
		(property "Description" ""
			(at 227.33 119.38 0)
			(effects
				(font
					(size 1.27 1.27)
				)
				(hide yes)
			)
		)
		(property "Author" "Antmicro"
			(at 236.22 127 0)
			(effects
				(font
					(size 1.27 1.27)
					(thickness 0.15)
				)
				(justify left bottom)
				(hide yes)
			)
		)
		(property "License" "Apache-2.0"
			(at 236.22 129.54 0)
			(effects
				(font
					(size 1.27 1.27)
					(thickness 0.15)
				)
				(justify left bottom)
				(hide yes)
			)
		)
		(pin "1"
		)
		(instances
			(project "OCuLink to 10GbE adapter"
				(path ""
					(reference "#PWR028")
					(unit 1)
				)
			)
		)
	)
	(symbol
		(lib_id "antmicroCapacitors0603:C_22u_16V_0603")
		(at 354.33 38.1 90)
		(unit 1)
		(exclude_from_sim no)
		(in_bom yes)
		(on_board yes)
		(dnp no)
		(property "Reference" "C8"
			(at 356.108 34.29 90)
			(effects
				(font
					(size 1.27 1.27)
					(thickness 0.15)
				)
				(justify right)
			)
		)
		(property "Value" "C_22u_16V_0603"
			(at 364.49 17.78 0)
			(effects
				(font
					(size 1.27 1.27)
					(thickness 0.15)
				)
				(justify left bottom)
				(hide yes)
			)
		)
		(property "Footprint" "antmicro-footprints:C_0603_1608Metric_EIA"
			(at 367.03 17.78 0)
			(effects
				(font
					(size 1.27 1.27)
					(thickness 0.15)
				)
				(justify left bottom)
				(hide yes)
			)
		)
		(property "Datasheet" "https://product.samsungsem.com/mlcc/CL10A226MO7JZN.do"
			(at 369.57 17.78 0)
			(effects
				(font
					(size 1.27 1.27)
					(thickness 0.15)
				)
				(justify left bottom)
				(hide yes)
			)
		)
		(property "Description" "SMD Multilayer Ceramic Capacitor"
			(at 354.33 38.1 0)
			(effects
				(font
					(size 1.27 1.27)
				)
				(hide yes)
			)
		)
		(property "MPN" "CL10A226MO7JZNC"
			(at 372.11 17.78 0)
			(effects
				(font
					(size 1.27 1.27)
					(thickness 0.15)
				)
				(justify left bottom)
				(hide yes)
			)
		)
		(property "Manufacturer" "Samsung Electro-Mechanics"
			(at 374.65 17.78 0)
			(effects
				(font
					(size 1.27 1.27)
					(thickness 0.15)
				)
				(justify left bottom)
				(hide yes)
			)
		)
		(property "License" "Apache-2.0"
			(at 377.19 17.78 0)
			(effects
				(font
					(size 1.27 1.27)
					(thickness 0.15)
				)
				(justify left bottom)
				(hide yes)
			)
		)
		(property "Author" "Antmicro"
			(at 379.73 17.78 0)
			(effects
				(font
					(size 1.27 1.27)
					(thickness 0.15)
				)
				(justify left bottom)
				(hide yes)
			)
		)
		(property "Val" "22u"
			(at 356.108 36.83 90)
			(effects
				(font
					(size 1.27 1.27)
					(thickness 0.15)
				)
				(justify right)
			)
		)
		(property "Voltage" "16V"
			(at 356.87 38.0935 90)
			(effects
				(font
					(size 1.27 1.27)
				)
				(justify right)
				(hide yes)
			)
		)
		(property "Dielectric" ""
			(at 384.81 17.78 0)
			(effects
				(font
					(size 1.27 1.27)
				)
				(justify left bottom)
				(hide yes)
			)
		)
		(property "Public" "False"
			(at 387.35 17.78 0)
			(effects
				(font
					(size 1.27 1.27)
				)
				(justify left bottom)
				(hide yes)
			)
		)
		(pin "2"
		)
		(pin "1"
		)
		(instances
			(project "OCuLink to 10GbE adapter"
				(path ""
					(reference "C8")
					(unit 1)
				)
			)
		)
	)
	(symbol
		(lib_id "antmicroFixedInductors:L_1u_10A_Bourns-SRP4021HMT")
		(at 314.96 63.5 0)
		(unit 1)
		(exclude_from_sim no)
		(in_bom yes)
		(on_board yes)
		(dnp no)
		(fields_autoplaced yes)
		(property "Reference" "L2"
			(at 317.5 58.42 0)
			(effects
				(font
					(size 1.27 1.27)
					(thickness 0.15)
				)
			)
		)
		(property "Value" "L_1u_10A_Bourns-SRP4021HMT"
			(at 330.2 73.66 0)
			(effects
				(font
					(size 1.27 1.27)
					(thickness 0.15)
				)
				(justify left bottom)
				(hide yes)
			)
		)
		(property "Footprint" "antmicro-footprints:L_Bourns-SRP4021HMT"
			(at 330.2 76.2 0)
			(effects
				(font
					(size 1.27 1.27)
					(thickness 0.15)
				)
				(justify left bottom)
				(hide yes)
			)
		)
		(property "Datasheet" "https://www.mouser.com/datasheet/2/54/Bourns_04_01_2025_SRP4021HMT_Datasheet-3580094.pdf"
			(at 330.2 78.74 0)
			(effects
				(font
					(size 1.27 1.27)
					(thickness 0.15)
				)
				(justify left bottom)
				(hide yes)
			)
		)
		(property "Description" "Power Inductors - SMD Ind,4.1x4.2x1.9mm,1uH+/-20%,10A, Shielded"
			(at 330.2 81.28 0)
			(effects
				(font
					(size 1.27 1.27)
					(thickness 0.15)
				)
				(justify left bottom)
				(hide yes)
			)
		)
		(property "Val" "1u/10A"
			(at 317.5 60.96 0)
			(effects
				(font
					(size 1.27 1.27)
					(thickness 0.15)
				)
			)
		)
		(property "Manufacturer" "Bourns"
			(at 330.2 83.82 0)
			(effects
				(font
					(size 1.27 1.27)
					(thickness 0.15)
				)
				(justify left bottom)
				(hide yes)
			)
		)
		(property "MPN" "SRP4021HMT-1R0M"
			(at 330.2 86.36 0)
			(effects
				(font
					(size 1.27 1.27)
					(thickness 0.15)
				)
				(justify left bottom)
				(hide yes)
			)
		)
		(property "ISat" ""
			(at 328.93 80.01 0)
			(effects
				(font
					(size 1.27 1.27)
				)
				(justify left)
				(hide yes)
			)
		)
		(property "Isat" "8A"
			(at 330.2 88.9 0)
			(effects
				(font
					(size 1.27 1.27)
					(thickness 0.15)
				)
				(justify left bottom)
				(hide yes)
			)
		)
		(property "IMax" ""
			(at 328.93 83.82 0)
			(effects
				(font
					(size 1.27 1.27)
					(thickness 0.15)
				)
				(justify left bottom)
				(hide yes)
			)
		)
		(property "Imax" "10A"
			(at 330.2 91.44 0)
			(effects
				(font
					(size 1.27 1.27)
					(thickness 0.15)
				)
				(justify left bottom)
				(hide yes)
			)
		)
		(property "Size" "4.2x4.1"
			(at 330.2 93.98 0)
			(effects
				(font
					(size 1.27 1.27)
					(thickness 0.15)
				)
				(justify left bottom)
				(hide yes)
			)
		)
		(property "Author" "Antmicro"
			(at 330.2 96.52 0)
			(effects
				(font
					(size 1.27 1.27)
					(thickness 0.15)
				)
				(justify left bottom)
				(hide yes)
			)
		)
		(property "License" "Apache-2.0"
			(at 330.2 99.06 0)
			(effects
				(font
					(size 1.27 1.27)
					(thickness 0.15)
				)
				(justify left bottom)
				(hide yes)
			)
		)
		(pin "1"
		)
		(pin "2"
		)
		(instances
			(project "OCuLink to 10GbE adapter"
				(path ""
					(reference "L2")
					(unit 1)
				)
			)
		)
	)
	(symbol
		(lib_name "TPS566231P_1")
		(lib_id "antmicroDCDCConverters:TPS566231P")
		(at 276.86 25.4 0)
		(unit 1)
		(exclude_from_sim no)
		(in_bom yes)
		(on_board yes)
		(dnp no)
		(fields_autoplaced yes)
		(property "Reference" "U1"
			(at 285.75 19.05 0)
			(effects
				(font
					(size 1.27 1.27)
					(thickness 0.15)
				)
			)
		)
		(property "Value" "TPS566231P"
			(at 309.88 30.48 0)
			(effects
				(font
					(size 1.27 1.27)
					(thickness 0.15)
				)
				(justify left bottom)
				(hide yes)
			)
		)
		(property "Footprint" "antmicro-footprints:VQFN-HR-9_2x1.5mm"
			(at 309.88 33.02 0)
			(effects
				(font
					(size 1.27 1.27)
					(thickness 0.15)
				)
				(justify left bottom)
				(hide yes)
			)
		)
		(property "Datasheet" "https://www.ti.com/lit/ds/symlink/tps566231.pdf"
			(at 309.88 35.56 0)
			(effects
				(font
					(size 1.27 1.27)
					(thickness 0.15)
				)
				(justify left bottom)
				(hide yes)
			)
		)
		(property "Description" "Switching Voltage Regulators 3-V to 18-V, 6-A synchronous buck converter"
			(at 309.88 48.26 0)
			(effects
				(font
					(size 1.27 1.27)
				)
				(justify left bottom)
				(hide yes)
			)
		)
		(property "Manufacturer" "Texas Instruments"
			(at 309.88 38.1 0)
			(effects
				(font
					(size 1.27 1.27)
					(thickness 0.15)
				)
				(justify left bottom)
				(hide yes)
			)
		)
		(property "MPN" "TPS566231PRQFR"
			(at 285.75 21.59 0)
			(effects
				(font
					(size 1.27 1.27)
					(thickness 0.15)
				)
			)
		)
		(property "Author" "Antmicro"
			(at 309.88 43.18 0)
			(effects
				(font
					(size 1.27 1.27)
					(thickness 0.15)
				)
				(justify left bottom)
				(hide yes)
			)
		)
		(property "License" "Apache-2.0"
			(at 309.88 45.72 0)
			(effects
				(font
					(size 1.27 1.27)
					(thickness 0.15)
				)
				(justify left bottom)
				(hide yes)
			)
		)
		(pin "1"
		)
		(pin "2"
		)
		(pin "3"
		)
		(pin "9"
		)
		(pin "5"
		)
		(pin "6"
		)
		(pin "8"
		)
		(pin "4"
		)
		(pin "7"
		)
		(instances
			(project ""
				(path ""
					(reference "U1")
					(unit 1)
				)
			)
		)
	)
	(symbol
		(lib_id "antmicroCapacitors0603:C_22u_16V_0603")
		(at 227.33 190.5 270)
		(mirror x)
		(unit 1)
		(exclude_from_sim no)
		(in_bom yes)
		(on_board yes)
		(dnp no)
		(property "Reference" "C41"
			(at 225.552 186.69 90)
			(effects
				(font
					(size 1.27 1.27)
					(thickness 0.15)
				)
				(justify right)
			)
		)
		(property "Value" "C_22u_16V_0603"
			(at 217.17 170.18 0)
			(effects
				(font
					(size 1.27 1.27)
					(thickness 0.15)
				)
				(justify left bottom)
				(hide yes)
			)
		)
		(property "Footprint" "antmicro-footprints:C_0603_1608Metric_EIA"
			(at 214.63 170.18 0)
			(effects
				(font
					(size 1.27 1.27)
					(thickness 0.15)
				)
				(justify left bottom)
				(hide yes)
			)
		)
		(property "Datasheet" "https://product.samsungsem.com/mlcc/CL10A226MO7JZN.do"
			(at 212.09 170.18 0)
			(effects
				(font
					(size 1.27 1.27)
					(thickness 0.15)
				)
				(justify left bottom)
				(hide yes)
			)
		)
		(property "Description" "SMD Multilayer Ceramic Capacitor"
			(at 227.33 190.5 0)
			(effects
				(font
					(size 1.27 1.27)
				)
				(hide yes)
			)
		)
		(property "MPN" "CL10A226MO7JZNC"
			(at 209.55 170.18 0)
			(effects
				(font
					(size 1.27 1.27)
					(thickness 0.15)
				)
				(justify left bottom)
				(hide yes)
			)
		)
		(property "Manufacturer" "Samsung Electro-Mechanics"
			(at 207.01 170.18 0)
			(effects
				(font
					(size 1.27 1.27)
					(thickness 0.15)
				)
				(justify left bottom)
				(hide yes)
			)
		)
		(property "License" "Apache-2.0"
			(at 204.47 170.18 0)
			(effects
				(font
					(size 1.27 1.27)
					(thickness 0.15)
				)
				(justify left bottom)
				(hide yes)
			)
		)
		(property "Author" "Antmicro"
			(at 201.93 170.18 0)
			(effects
				(font
					(size 1.27 1.27)
					(thickness 0.15)
				)
				(justify left bottom)
				(hide yes)
			)
		)
		(property "Val" "22u"
			(at 225.552 189.23 90)
			(effects
				(font
					(size 1.27 1.27)
					(thickness 0.15)
				)
				(justify right)
			)
		)
		(property "Voltage" "16V"
			(at 224.79 190.4935 90)
			(effects
				(font
					(size 1.27 1.27)
				)
				(justify right)
				(hide yes)
			)
		)
		(property "Dielectric" ""
			(at 196.85 170.18 0)
			(effects
				(font
					(size 1.27 1.27)
				)
				(justify left bottom)
				(hide yes)
			)
		)
		(property "Public" "False"
			(at 194.31 170.18 0)
			(effects
				(font
					(size 1.27 1.27)
				)
				(justify left bottom)
				(hide yes)
			)
		)
		(pin "2"
		)
		(pin "1"
		)
		(instances
			(project "OCuLink to 10GbE adapter"
				(path ""
					(reference "C41")
					(unit 1)
				)
			)
		)
	)
	(symbol
		(lib_id "antmicroResistors0402:R_100k_0402")
		(at 256.54 152.4 270)
		(mirror x)
		(unit 1)
		(exclude_from_sim no)
		(in_bom yes)
		(on_board yes)
		(dnp no)
		(property "Reference" "R25"
			(at 255.27 148.59 90)
			(effects
				(font
					(size 1.27 1.27)
					(thickness 0.15)
				)
				(justify right)
			)
		)
		(property "Value" "R_100k_0402"
			(at 243.84 132.08 0)
			(effects
				(font
					(size 1.27 1.27)
					(thickness 0.15)
				)
				(justify left bottom)
				(hide yes)
			)
		)
		(property "Footprint" "antmicro-footprints:R_0402_1005Metric"
			(at 241.3 132.08 0)
			(effects
				(font
					(size 1.27 1.27)
					(thickness 0.15)
				)
				(justify left bottom)
				(hide yes)
			)
		)
		(property "Datasheet" "https://www.bourns.com/docs/product-datasheets/cr.pdf"
			(at 238.76 132.08 0)
			(effects
				(font
					(size 1.27 1.27)
					(thickness 0.15)
				)
				(justify left bottom)
				(hide yes)
			)
		)
		(property "Description" "SMD Chip Resistor, 100 kohm, ± 1%, 62.5 mW, 0402 [1005 Metric], Thick Film, General Purpose"
			(at 226.06 132.08 0)
			(effects
				(font
					(size 1.27 1.27)
				)
				(justify left bottom)
				(hide yes)
			)
		)
		(property "MPN" "CR0402-FX-1003GLF"
			(at 236.22 132.08 0)
			(effects
				(font
					(size 1.27 1.27)
					(thickness 0.15)
				)
				(justify left bottom)
				(hide yes)
			)
		)
		(property "Manufacturer" "Bourns"
			(at 233.68 132.08 0)
			(effects
				(font
					(size 1.27 1.27)
					(thickness 0.15)
				)
				(justify left bottom)
				(hide yes)
			)
		)
		(property "License" "Apache-2.0"
			(at 231.14 132.08 0)
			(effects
				(font
					(size 1.27 1.27)
					(thickness 0.15)
				)
				(justify left bottom)
				(hide yes)
			)
		)
		(property "Author" "Antmicro"
			(at 228.6 132.08 0)
			(effects
				(font
					(size 1.27 1.27)
					(thickness 0.15)
				)
				(justify left bottom)
				(hide yes)
			)
		)
		(property "Val" "100k"
			(at 255.27 151.13 90)
			(effects
				(font
					(size 1.27 1.27)
					(thickness 0.15)
				)
				(justify right)
			)
		)
		(property "Tolerance" "1%"
			(at 246.38 132.08 0)
			(effects
				(font
					(size 1.27 1.27)
				)
				(justify left bottom)
				(hide yes)
			)
		)
		(pin "1"
		)
		(pin "2"
		)
		(instances
			(project "OCuLink to 10GbE adapter"
				(path ""
					(reference "R25")
					(unit 1)
				)
			)
		)
	)
	(symbol
		(lib_id "antmicropower:GND")
		(at 344.17 195.58 0)
		(unit 1)
		(exclude_from_sim no)
		(in_bom yes)
		(on_board yes)
		(dnp no)
		(property "Reference" "#PWR059"
			(at 353.06 198.12 0)
			(effects
				(font
					(size 1.27 1.27)
					(thickness 0.15)
				)
				(justify left bottom)
				(hide yes)
			)
		)
		(property "Value" "GND"
			(at 344.17 199.39 0)
			(effects
				(font
					(size 1.27 1.27)
					(thickness 0.15)
				)
			)
		)
		(property "Footprint" ""
			(at 353.06 203.2 0)
			(effects
				(font
					(size 1.27 1.27)
					(thickness 0.15)
				)
				(justify left bottom)
				(hide yes)
			)
		)
		(property "Datasheet" ""
			(at 353.06 208.28 0)
			(effects
				(font
					(size 1.27 1.27)
					(thickness 0.15)
				)
				(justify left bottom)
				(hide yes)
			)
		)
		(property "Description" ""
			(at 344.17 195.58 0)
			(effects
				(font
					(size 1.27 1.27)
				)
				(hide yes)
			)
		)
		(property "Author" "Antmicro"
			(at 353.06 203.2 0)
			(effects
				(font
					(size 1.27 1.27)
					(thickness 0.15)
				)
				(justify left bottom)
				(hide yes)
			)
		)
		(property "License" "Apache-2.0"
			(at 353.06 205.74 0)
			(effects
				(font
					(size 1.27 1.27)
					(thickness 0.15)
				)
				(justify left bottom)
				(hide yes)
			)
		)
		(pin "1"
		)
		(instances
			(project "OCuLink to 10GbE adapter"
				(path ""
					(reference "#PWR059")
					(unit 1)
				)
			)
		)
	)
	(symbol
		(lib_id "antmicropower:VCC")
		(at 217.17 99.06 0)
		(unit 1)
		(exclude_from_sim no)
		(in_bom yes)
		(on_board yes)
		(dnp no)
		(property "Reference" "#PWR0355"
			(at 217.17 102.87 0)
			(effects
				(font
					(size 1.27 1.27)
				)
				(hide yes)
			)
		)
		(property "Value" "VCC"
			(at 217.17 95.25 0)
			(effects
				(font
					(size 1.27 1.27)
				)
			)
		)
		(property "Footprint" ""
			(at 217.17 99.06 0)
			(effects
				(font
					(size 1.27 1.27)
				)
				(hide yes)
			)
		)
		(property "Datasheet" ""
			(at 217.17 99.06 0)
			(effects
				(font
					(size 1.27 1.27)
				)
				(hide yes)
			)
		)
		(property "Description" ""
			(at 217.17 105.41 0)
			(effects
				(font
					(size 1.27 1.27)
				)
				(justify left bottom)
				(hide yes)
			)
		)
		(pin "1"
		)
		(instances
			(project "oculink-to-10gbe-adapter"
				(path ""
					(reference "#PWR0355")
					(unit 1)
				)
			)
		)
	)
	(symbol
		(lib_id "antmicroResistors0402:R_63k4_0402")
		(at 332.74 109.22 90)
		(unit 1)
		(exclude_from_sim no)
		(in_bom yes)
		(on_board yes)
		(dnp no)
		(property "Reference" "R15"
			(at 334.01 105.41 90)
			(effects
				(font
					(size 1.27 1.27)
					(thickness 0.15)
				)
				(justify right)
			)
		)
		(property "Value" "R_63k4_0402"
			(at 345.44 88.9 0)
			(effects
				(font
					(size 1.27 1.27)
					(thickness 0.15)
				)
				(justify left bottom)
				(hide yes)
			)
		)
		(property "Footprint" "antmicro-footprints:R_0402_1005Metric"
			(at 347.98 88.9 0)
			(effects
				(font
					(size 1.27 1.27)
					(thickness 0.15)
				)
				(justify left bottom)
				(hide yes)
			)
		)
		(property "Datasheet" "https://industrial.panasonic.com/cdbs/www-data/pdf/RDM0000/AOA0000C307.pdf"
			(at 350.52 88.9 0)
			(effects
				(font
					(size 1.27 1.27)
					(thickness 0.15)
				)
				(justify left bottom)
				(hide yes)
			)
		)
		(property "Description" "SMD Chip Resistor, 63.4 kohm, ± 0.1%, 63 mW, 0402 [1005 Metric], Thin Film,  Precision"
			(at 363.22 88.9 0)
			(effects
				(font
					(size 1.27 1.27)
				)
				(justify left bottom)
				(hide yes)
			)
		)
		(property "MPN" "ERA-2AEB6342X"
			(at 353.06 88.9 0)
			(effects
				(font
					(size 1.27 1.27)
					(thickness 0.15)
				)
				(justify left bottom)
				(hide yes)
			)
		)
		(property "Manufacturer" "Panasonic"
			(at 355.6 88.9 0)
			(effects
				(font
					(size 1.27 1.27)
					(thickness 0.15)
				)
				(justify left bottom)
				(hide yes)
			)
		)
		(property "License" "Apache-2.0"
			(at 358.14 88.9 0)
			(effects
				(font
					(size 1.27 1.27)
					(thickness 0.15)
				)
				(justify left bottom)
				(hide yes)
			)
		)
		(property "Author" "Antmicro"
			(at 360.68 88.9 0)
			(effects
				(font
					(size 1.27 1.27)
					(thickness 0.15)
				)
				(justify left bottom)
				(hide yes)
			)
		)
		(property "Val" "63k4"
			(at 334.01 107.95 90)
			(effects
				(font
					(size 1.27 1.27)
					(thickness 0.15)
				)
				(justify right)
			)
		)
		(property "Tolerance" "0.1%"
			(at 342.9 88.9 0)
			(effects
				(font
					(size 1.27 1.27)
				)
				(justify left bottom)
				(hide yes)
			)
		)
		(pin "2"
		)
		(pin "1"
		)
		(instances
			(project "OCuLink to 10GbE adapter"
				(path ""
					(reference "R15")
					(unit 1)
				)
			)
		)
	)
	(symbol
		(lib_id "antmicroResistors0603:R_0R_22.4A_0603")
		(at 379.73 177.8 0)
		(unit 1)
		(exclude_from_sim no)
		(in_bom yes)
		(on_board yes)
		(dnp no)
		(property "Reference" "R28"
			(at 379.73 176.53 0)
			(effects
				(font
					(size 1.27 1.27)
					(thickness 0.15)
				)
				(justify right)
			)
		)
		(property "Value" "R_0R_22.4A_0603"
			(at 394.97 182.88 0)
			(effects
				(font
					(size 1.27 1.27)
					(thickness 0.15)
				)
				(justify left bottom)
				(hide yes)
			)
		)
		(property "Footprint" "antmicro-footprints:R_0603_1608Metric"
			(at 394.97 187.96 0)
			(effects
				(font
					(size 1.27 1.27)
					(thickness 0.15)
				)
				(justify left bottom)
				(hide yes)
			)
		)
		(property "Datasheet" "https://fscdn.rohm.com/en/products/databook/datasheet/passive/resistor/chip_resistor/pmr-jpw-e.pdf"
			(at 394.97 190.5 0)
			(effects
				(font
					(size 1.27 1.27)
					(thickness 0.15)
				)
				(justify left bottom)
				(hide yes)
			)
		)
		(property "Description" "SMD Chip Resistor"
			(at 394.97 205.74 0)
			(effects
				(font
					(size 1.27 1.27)
				)
				(justify left bottom)
				(hide yes)
			)
		)
		(property "MPN" "PMR03EZPJ000"
			(at 394.97 193.04 0)
			(effects
				(font
					(size 1.27 1.27)
					(thickness 0.15)
				)
				(justify left bottom)
				(hide yes)
			)
		)
		(property "Manufacturer" "ROHM Semiconductor"
			(at 394.97 195.58 0)
			(effects
				(font
					(size 1.27 1.27)
					(thickness 0.15)
				)
				(justify left bottom)
				(hide yes)
			)
		)
		(property "Val" "0R"
			(at 384.81 176.53 0)
			(effects
				(font
					(size 1.27 1.27)
					(thickness 0.15)
				)
				(justify left)
			)
		)
		(property "Max. Curr." "22.4A"
			(at 382.27 180.34 0)
			(effects
				(font
					(size 1.27 1.27)
					(thickness 0.15)
				)
			)
		)
		(property "Author" "Antmicro"
			(at 394.97 200.66 0)
			(effects
				(font
					(size 1.27 1.27)
					(thickness 0.15)
				)
				(justify left bottom)
				(hide yes)
			)
		)
		(property "License" "Apache-2.0"
			(at 394.97 203.2 0)
			(effects
				(font
					(size 1.27 1.27)
					(thickness 0.15)
				)
				(justify left bottom)
				(hide yes)
			)
		)
		(property "Tolerance" "template_tolerance"
			(at 400.05 187.96 0)
			(effects
				(font
					(size 1.27 1.27)
				)
				(justify left bottom)
				(hide yes)
			)
		)
		(pin "1"
		)
		(pin "2"
		)
		(instances
			(project "OCuLink to 10GbE adapter"
				(path ""
					(reference "R28")
					(unit 1)
				)
			)
		)
	)
	(symbol
		(lib_id "antmicropower:+3V3")
		(at 304.8 213.36 0)
		(unit 1)
		(exclude_from_sim no)
		(in_bom yes)
		(on_board yes)
		(dnp no)
		(property "Reference" "#PWR0333"
			(at 320.04 213.36 0)
			(effects
				(font
					(size 1.27 1.27)
					(thickness 0.15)
				)
				(justify left bottom)
				(hide yes)
			)
		)
		(property "Value" "+3V3"
			(at 304.8 209.55 0)
			(effects
				(font
					(size 1.27 1.27)
					(thickness 0.15)
				)
			)
		)
		(property "Footprint" ""
			(at 320.04 220.98 0)
			(effects
				(font
					(size 1.27 1.27)
					(thickness 0.15)
				)
				(justify left bottom)
				(hide yes)
			)
		)
		(property "Datasheet" ""
			(at 320.04 223.52 0)
			(effects
				(font
					(size 1.27 1.27)
					(thickness 0.15)
				)
				(justify left bottom)
				(hide yes)
			)
		)
		(property "Description" ""
			(at 304.8 213.36 0)
			(effects
				(font
					(size 1.27 1.27)
				)
				(hide yes)
			)
		)
		(property "Author" "Antmicro"
			(at 320.04 215.9 0)
			(effects
				(font
					(size 1.27 1.27)
					(thickness 0.15)
				)
				(justify left bottom)
				(hide yes)
			)
		)
		(property "License" "Apache-2.0"
			(at 320.04 218.44 0)
			(effects
				(font
					(size 1.27 1.27)
					(thickness 0.15)
				)
				(justify left bottom)
				(hide yes)
			)
		)
		(pin "1"
		)
		(instances
			(project "OCuLink to 10GbE adapter"
				(path ""
					(reference "#PWR0333")
					(unit 1)
				)
			)
		)
	)
	(symbol
		(lib_id "antmicropower:PWR_FLAG")
		(at 391.16 22.86 0)
		(unit 1)
		(exclude_from_sim no)
		(in_bom yes)
		(on_board yes)
		(dnp no)
		(property "Reference" "#FLG01"
			(at 391.16 20.955 0)
			(effects
				(font
					(size 1.27 1.27)
				)
				(hide yes)
			)
		)
		(property "Value" "PWR_FLAG"
			(at 391.16 19.05 0)
			(effects
				(font
					(size 1.27 1.27)
				)
			)
		)
		(property "Footprint" ""
			(at 391.16 22.86 0)
			(effects
				(font
					(size 1.27 1.27)
				)
				(hide yes)
			)
		)
		(property "Datasheet" ""
			(at 391.16 22.86 0)
			(effects
				(font
					(size 1.27 1.27)
				)
				(hide yes)
			)
		)
		(property "Description" ""
			(at 391.16 22.86 0)
			(effects
				(font
					(size 1.27 1.27)
				)
				(hide yes)
			)
		)
		(pin "1"
		)
		(instances
			(project "OCuLink to 10GbE adapter"
				(path ""
					(reference "#FLG01")
					(unit 1)
				)
			)
		)
	)
	(symbol
		(lib_id "antmicroResistors0402:R_1k_0402")
		(at 203.2 231.14 90)
		(unit 1)
		(exclude_from_sim no)
		(in_bom yes)
		(on_board yes)
		(dnp no)
		(property "Reference" "R145"
			(at 204.47 227.33 90)
			(effects
				(font
					(size 1.27 1.27)
					(thickness 0.15)
				)
				(justify right)
			)
		)
		(property "Value" "R_1k_0402"
			(at 215.9 210.82 0)
			(effects
				(font
					(size 1.27 1.27)
					(thickness 0.15)
				)
				(justify left bottom)
				(hide yes)
			)
		)
		(property "Footprint" "antmicro-footprints:R_0402_1005Metric"
			(at 218.44 210.82 0)
			(effects
				(font
					(size 1.27 1.27)
					(thickness 0.15)
				)
				(justify left bottom)
				(hide yes)
			)
		)
		(property "Datasheet" "https://www.bourns.com/docs/product-datasheets/cr.pdf"
			(at 220.98 210.82 0)
			(effects
				(font
					(size 1.27 1.27)
					(thickness 0.15)
				)
				(justify left bottom)
				(hide yes)
			)
		)
		(property "Description" "SMD Chip Resistor, 1 kohm, ± 1%, 63 mW, 0402 [1005 Metric], Thick Film, General Purpose"
			(at 233.68 210.82 0)
			(effects
				(font
					(size 1.27 1.27)
				)
				(justify left bottom)
				(hide yes)
			)
		)
		(property "MPN" "CR0402-FX-1001GLF"
			(at 223.52 210.82 0)
			(effects
				(font
					(size 1.27 1.27)
					(thickness 0.15)
				)
				(justify left bottom)
				(hide yes)
			)
		)
		(property "Manufacturer" "Bourns"
			(at 226.06 210.82 0)
			(effects
				(font
					(size 1.27 1.27)
					(thickness 0.15)
				)
				(justify left bottom)
				(hide yes)
			)
		)
		(property "License" "Apache-2.0"
			(at 228.6 210.82 0)
			(effects
				(font
					(size 1.27 1.27)
					(thickness 0.15)
				)
				(justify left bottom)
				(hide yes)
			)
		)
		(property "Author" "Antmicro"
			(at 231.14 210.82 0)
			(effects
				(font
					(size 1.27 1.27)
					(thickness 0.15)
				)
				(justify left bottom)
				(hide yes)
			)
		)
		(property "Val" "1k"
			(at 204.47 229.87 90)
			(effects
				(font
					(size 1.27 1.27)
					(thickness 0.15)
				)
				(justify right)
			)
		)
		(property "Tolerance" "1%"
			(at 213.36 210.82 0)
			(effects
				(font
					(size 1.27 1.27)
				)
				(justify left bottom)
				(hide yes)
			)
		)
		(pin "1"
		)
		(pin "2"
		)
		(instances
			(project "oculink-to-10gbe-adapter"
				(path ""
					(reference "R145")
					(unit 1)
				)
			)
		)
	)
	(symbol
		(lib_id "antmicroResistors0402:R_10k_0402")
		(at 83.82 92.71 90)
		(unit 1)
		(exclude_from_sim no)
		(in_bom yes)
		(on_board yes)
		(dnp no)
		(property "Reference" "R13"
			(at 85.09 88.9 90)
			(effects
				(font
					(size 1.27 1.27)
					(thickness 0.15)
				)
				(justify right)
			)
		)
		(property "Value" "R_10k_0402"
			(at 96.52 72.39 0)
			(effects
				(font
					(size 1.27 1.27)
					(thickness 0.15)
				)
				(justify left bottom)
				(hide yes)
			)
		)
		(property "Footprint" "antmicro-footprints:R_0402_1005Metric"
			(at 99.06 72.39 0)
			(effects
				(font
					(size 1.27 1.27)
					(thickness 0.15)
				)
				(justify left bottom)
				(hide yes)
			)
		)
		(property "Datasheet" "https://www.bourns.com/docs/product-datasheets/cr.pdf"
			(at 101.6 72.39 0)
			(effects
				(font
					(size 1.27 1.27)
					(thickness 0.15)
				)
				(justify left bottom)
				(hide yes)
			)
		)
		(property "Description" "SMD Chip Resistor, 10 kohm, ± 1%, 62.5 mW, 0402 [1005 Metric], Thick Film, General Purpose"
			(at 83.82 92.71 0)
			(effects
				(font
					(size 1.27 1.27)
				)
				(hide yes)
			)
		)
		(property "MPN" "CR0402-FX-1002GLF"
			(at 104.14 72.39 0)
			(effects
				(font
					(size 1.27 1.27)
					(thickness 0.15)
				)
				(justify left bottom)
				(hide yes)
			)
		)
		(property "Manufacturer" "Bourns"
			(at 106.68 72.39 0)
			(effects
				(font
					(size 1.27 1.27)
					(thickness 0.15)
				)
				(justify left bottom)
				(hide yes)
			)
		)
		(property "License" "Apache-2.0"
			(at 109.22 72.39 0)
			(effects
				(font
					(size 1.27 1.27)
					(thickness 0.15)
				)
				(justify left bottom)
				(hide yes)
			)
		)
		(property "Author" "Antmicro"
			(at 111.76 72.39 0)
			(effects
				(font
					(size 1.27 1.27)
					(thickness 0.15)
				)
				(justify left bottom)
				(hide yes)
			)
		)
		(property "Val" "10k"
			(at 85.09 91.44 90)
			(effects
				(font
					(size 1.27 1.27)
					(thickness 0.15)
				)
				(justify right)
			)
		)
		(property "Tolerance" "1%"
			(at 93.98 72.39 0)
			(effects
				(font
					(size 1.27 1.27)
				)
				(justify left bottom)
				(hide yes)
			)
		)
		(pin "2"
		)
		(pin "1"
		)
		(instances
			(project ""
				(path ""
					(reference "R13")
					(unit 1)
				)
			)
		)
	)
	(symbol
		(lib_id "antmicropower:PWR_FLAG")
		(at 133.35 82.55 0)
		(unit 1)
		(exclude_from_sim no)
		(in_bom yes)
		(on_board yes)
		(dnp no)
		(property "Reference" "#FLG04"
			(at 133.35 80.645 0)
			(effects
				(font
					(size 1.27 1.27)
				)
				(hide yes)
			)
		)
		(property "Value" "PWR_FLAG"
			(at 133.35 78.74 0)
			(effects
				(font
					(size 1.27 1.27)
				)
			)
		)
		(property "Footprint" ""
			(at 133.35 82.55 0)
			(effects
				(font
					(size 1.27 1.27)
				)
				(hide yes)
			)
		)
		(property "Datasheet" ""
			(at 133.35 82.55 0)
			(effects
				(font
					(size 1.27 1.27)
				)
				(hide yes)
			)
		)
		(property "Description" ""
			(at 133.35 82.55 0)
			(effects
				(font
					(size 1.27 1.27)
				)
				(hide yes)
			)
		)
		(pin "1"
		)
		(instances
			(project "OCuLink to 10GbE adapter"
				(path ""
					(reference "#FLG04")
					(unit 1)
				)
			)
		)
	)
	(symbol
		(lib_id "antmicroTestPoints:TP_0.75mm_SMD")
		(at 138.43 87.63 270)
		(unit 1)
		(exclude_from_sim no)
		(in_bom no)
		(on_board yes)
		(dnp no)
		(property "Reference" "TP22"
			(at 138.43 92.71 90)
			(effects
				(font
					(size 1.27 1.27)
					(thickness 0.15)
				)
			)
		)
		(property "Value" "TP_0.75mm_SMD"
			(at 134.62 97.79 0)
			(effects
				(font
					(size 1.27 1.27)
					(thickness 0.15)
				)
				(justify left bottom)
				(hide yes)
			)
		)
		(property "Footprint" "antmicro-footprints:TP_SMD_0.75mm"
			(at 132.08 97.79 0)
			(effects
				(font
					(size 1.27 1.27)
					(thickness 0.15)
				)
				(justify left bottom)
				(hide yes)
			)
		)
		(property "Datasheet" ""
			(at 125.73 105.41 0)
			(effects
				(font
					(size 1.27 1.27)
					(thickness 0.15)
				)
				(justify left bottom)
				(hide yes)
			)
		)
		(property "Description" "SMT test point"
			(at 138.43 87.63 0)
			(effects
				(font
					(size 1.27 1.27)
				)
				(hide yes)
			)
		)
		(property "MPN" ""
			(at 127 98.425 0)
			(effects
				(font
					(size 1.27 1.27)
					(thickness 0.15)
				)
				(justify left bottom)
				(hide yes)
			)
		)
		(property "Manufacturer" ""
			(at 132.08 98.425 0)
			(effects
				(font
					(size 1.27 1.27)
					(thickness 0.15)
				)
				(justify left bottom)
				(hide yes)
			)
		)
		(property "Author" "Antmicro"
			(at 129.54 97.79 0)
			(effects
				(font
					(size 1.27 1.27)
					(thickness 0.15)
				)
				(justify left bottom)
				(hide yes)
			)
		)
		(property "License" "Apache-2.0"
			(at 127 97.79 0)
			(effects
				(font
					(size 1.27 1.27)
					(thickness 0.15)
				)
				(justify left bottom)
				(hide yes)
			)
		)
		(pin "1"
		)
		(instances
			(project "OCuLink to 10GbE adapter"
				(path ""
					(reference "TP22")
					(unit 1)
				)
			)
		)
	)
	(symbol
		(lib_id "antmicroResistors0402:R_5k1_0402")
		(at 76.2 149.86 270)
		(mirror x)
		(unit 1)
		(exclude_from_sim no)
		(in_bom yes)
		(on_board yes)
		(dnp no)
		(property "Reference" "R22"
			(at 74.93 146.05 90)
			(effects
				(font
					(size 1.27 1.27)
					(thickness 0.15)
				)
				(justify right)
			)
		)
		(property "Value" "R_5k1_0402"
			(at 63.5 129.54 0)
			(effects
				(font
					(size 1.27 1.27)
					(thickness 0.15)
				)
				(justify left bottom)
				(hide yes)
			)
		)
		(property "Footprint" "antmicro-footprints:R_0402_1005Metric"
			(at 60.96 129.54 0)
			(effects
				(font
					(size 1.27 1.27)
					(thickness 0.15)
				)
				(justify left bottom)
				(hide yes)
			)
		)
		(property "Datasheet" "https://www.bourns.com/docs/product-datasheets/cr.pdf"
			(at 58.42 129.54 0)
			(effects
				(font
					(size 1.27 1.27)
					(thickness 0.15)
				)
				(justify left bottom)
				(hide yes)
			)
		)
		(property "Description" "SMD Chip Resistor, 5.1 kohm, ± 1%, 63 mW, 0402 [1005 Metric], Thick Film, General Purpose"
			(at 76.2 149.86 0)
			(effects
				(font
					(size 1.27 1.27)
				)
				(hide yes)
			)
		)
		(property "MPN" "CR0402-FX-5101GLF"
			(at 55.88 129.54 0)
			(effects
				(font
					(size 1.27 1.27)
					(thickness 0.15)
				)
				(justify left bottom)
				(hide yes)
			)
		)
		(property "Manufacturer" "Bourns"
			(at 53.34 129.54 0)
			(effects
				(font
					(size 1.27 1.27)
					(thickness 0.15)
				)
				(justify left bottom)
				(hide yes)
			)
		)
		(property "License" "Apache-2.0"
			(at 50.8 129.54 0)
			(effects
				(font
					(size 1.27 1.27)
					(thickness 0.15)
				)
				(justify left bottom)
				(hide yes)
			)
		)
		(property "Author" "Antmicro"
			(at 48.26 129.54 0)
			(effects
				(font
					(size 1.27 1.27)
					(thickness 0.15)
				)
				(justify left bottom)
				(hide yes)
			)
		)
		(property "Val" "5k1"
			(at 74.93 148.59 90)
			(effects
				(font
					(size 1.27 1.27)
					(thickness 0.15)
				)
				(justify right)
			)
		)
		(property "Tolerance" "1%"
			(at 66.04 129.54 0)
			(effects
				(font
					(size 1.27 1.27)
				)
				(justify left bottom)
				(hide yes)
			)
		)
		(pin "2"
		)
		(pin "1"
		)
		(instances
			(project ""
				(path ""
					(reference "R22")
					(unit 1)
				)
			)
		)
	)
	(symbol
		(lib_id "antmicropower:+3V3")
		(at 400.05 22.86 0)
		(unit 1)
		(exclude_from_sim no)
		(in_bom yes)
		(on_board yes)
		(dnp no)
		(property "Reference" "#PWR02"
			(at 415.29 22.86 0)
			(effects
				(font
					(size 1.27 1.27)
					(thickness 0.15)
				)
				(justify left bottom)
				(hide yes)
			)
		)
		(property "Value" "+3V3"
			(at 400.05 19.05 0)
			(effects
				(font
					(size 1.27 1.27)
					(thickness 0.15)
				)
			)
		)
		(property "Footprint" ""
			(at 415.29 30.48 0)
			(effects
				(font
					(size 1.27 1.27)
					(thickness 0.15)
				)
				(justify left bottom)
				(hide yes)
			)
		)
		(property "Datasheet" ""
			(at 415.29 33.02 0)
			(effects
				(font
					(size 1.27 1.27)
					(thickness 0.15)
				)
				(justify left bottom)
				(hide yes)
			)
		)
		(property "Description" ""
			(at 400.05 22.86 0)
			(effects
				(font
					(size 1.27 1.27)
				)
				(hide yes)
			)
		)
		(property "Author" "Antmicro"
			(at 415.29 25.4 0)
			(effects
				(font
					(size 1.27 1.27)
					(thickness 0.15)
				)
				(justify left bottom)
				(hide yes)
			)
		)
		(property "License" "Apache-2.0"
			(at 415.29 27.94 0)
			(effects
				(font
					(size 1.27 1.27)
					(thickness 0.15)
				)
				(justify left bottom)
				(hide yes)
			)
		)
		(pin "1"
		)
		(instances
			(project "OCuLink to 10GbE adapter"
				(path ""
					(reference "#PWR02")
					(unit 1)
				)
			)
		)
	)
	(symbol
		(lib_id "antmicropower:GND")
		(at 177.8 246.38 0)
		(mirror y)
		(unit 1)
		(exclude_from_sim no)
		(in_bom yes)
		(on_board yes)
		(dnp no)
		(property "Reference" "#PWR0313"
			(at 168.91 248.92 0)
			(effects
				(font
					(size 1.27 1.27)
					(thickness 0.15)
				)
				(justify left bottom)
				(hide yes)
			)
		)
		(property "Value" "GND"
			(at 177.8 250.19 0)
			(effects
				(font
					(size 1.27 1.27)
					(thickness 0.15)
				)
			)
		)
		(property "Footprint" ""
			(at 168.91 254 0)
			(effects
				(font
					(size 1.27 1.27)
					(thickness 0.15)
				)
				(justify left bottom)
				(hide yes)
			)
		)
		(property "Datasheet" ""
			(at 168.91 259.08 0)
			(effects
				(font
					(size 1.27 1.27)
					(thickness 0.15)
				)
				(justify left bottom)
				(hide yes)
			)
		)
		(property "Description" ""
			(at 177.8 246.38 0)
			(effects
				(font
					(size 1.27 1.27)
				)
				(hide yes)
			)
		)
		(property "Author" "Antmicro"
			(at 168.91 254 0)
			(effects
				(font
					(size 1.27 1.27)
					(thickness 0.15)
				)
				(justify left bottom)
				(hide yes)
			)
		)
		(property "License" "Apache-2.0"
			(at 168.91 256.54 0)
			(effects
				(font
					(size 1.27 1.27)
					(thickness 0.15)
				)
				(justify left bottom)
				(hide yes)
			)
		)
		(pin "1"
		)
		(instances
			(project "oculink-to-10gbe-adapter"
				(path ""
					(reference "#PWR0313")
					(unit 1)
				)
			)
		)
	)
	(symbol
		(lib_id "antmicropower:PWR_FLAG")
		(at 101.6 170.18 0)
		(unit 1)
		(exclude_from_sim no)
		(in_bom yes)
		(on_board yes)
		(dnp no)
		(property "Reference" "#FLG08"
			(at 101.6 168.275 0)
			(effects
				(font
					(size 1.27 1.27)
				)
				(hide yes)
			)
		)
		(property "Value" "PWR_FLAG"
			(at 101.6 166.116 0)
			(effects
				(font
					(size 1.27 1.27)
				)
			)
		)
		(property "Footprint" ""
			(at 101.6 170.18 0)
			(effects
				(font
					(size 1.27 1.27)
				)
				(hide yes)
			)
		)
		(property "Datasheet" ""
			(at 101.6 170.18 0)
			(effects
				(font
					(size 1.27 1.27)
				)
				(hide yes)
			)
		)
		(property "Description" ""
			(at 101.6 170.18 0)
			(effects
				(font
					(size 1.27 1.27)
				)
				(hide yes)
			)
		)
		(pin "1"
		)
		(instances
			(project "OCuLink to 10GbE adapter"
				(path ""
					(reference "#FLG08")
					(unit 1)
				)
			)
		)
	)
	(symbol
		(lib_id "antmicroCapacitors0603:C_22u_16V_0603")
		(at 344.17 114.3 90)
		(unit 1)
		(exclude_from_sim no)
		(in_bom yes)
		(on_board yes)
		(dnp no)
		(property "Reference" "C25"
			(at 346.202 110.49 90)
			(effects
				(font
					(size 1.27 1.27)
					(thickness 0.15)
				)
				(justify right)
			)
		)
		(property "Value" "C_22u_16V_0603"
			(at 354.33 93.98 0)
			(effects
				(font
					(size 1.27 1.27)
					(thickness 0.15)
				)
				(justify left bottom)
				(hide yes)
			)
		)
		(property "Footprint" "antmicro-footprints:C_0603_1608Metric_EIA"
			(at 356.87 93.98 0)
			(effects
				(font
					(size 1.27 1.27)
					(thickness 0.15)
				)
				(justify left bottom)
				(hide yes)
			)
		)
		(property "Datasheet" "https://product.samsungsem.com/mlcc/CL10A226MO7JZN.do"
			(at 359.41 93.98 0)
			(effects
				(font
					(size 1.27 1.27)
					(thickness 0.15)
				)
				(justify left bottom)
				(hide yes)
			)
		)
		(property "Description" "SMD Multilayer Ceramic Capacitor"
			(at 344.17 114.3 0)
			(effects
				(font
					(size 1.27 1.27)
				)
				(hide yes)
			)
		)
		(property "MPN" "CL10A226MO7JZNC"
			(at 361.95 93.98 0)
			(effects
				(font
					(size 1.27 1.27)
					(thickness 0.15)
				)
				(justify left bottom)
				(hide yes)
			)
		)
		(property "Manufacturer" "Samsung Electro-Mechanics"
			(at 364.49 93.98 0)
			(effects
				(font
					(size 1.27 1.27)
					(thickness 0.15)
				)
				(justify left bottom)
				(hide yes)
			)
		)
		(property "License" "Apache-2.0"
			(at 367.03 93.98 0)
			(effects
				(font
					(size 1.27 1.27)
					(thickness 0.15)
				)
				(justify left bottom)
				(hide yes)
			)
		)
		(property "Author" "Antmicro"
			(at 369.57 93.98 0)
			(effects
				(font
					(size 1.27 1.27)
					(thickness 0.15)
				)
				(justify left bottom)
				(hide yes)
			)
		)
		(property "Val" "22u"
			(at 346.202 113.03 90)
			(effects
				(font
					(size 1.27 1.27)
					(thickness 0.15)
				)
				(justify right)
			)
		)
		(property "Voltage" "16V"
			(at 346.71 114.2935 90)
			(effects
				(font
					(size 1.27 1.27)
				)
				(justify right)
				(hide yes)
			)
		)
		(property "Dielectric" ""
			(at 374.65 93.98 0)
			(effects
				(font
					(size 1.27 1.27)
				)
				(justify left bottom)
				(hide yes)
			)
		)
		(property "Public" "False"
			(at 377.19 93.98 0)
			(effects
				(font
					(size 1.27 1.27)
				)
				(justify left bottom)
				(hide yes)
			)
		)
		(pin "2"
		)
		(pin "1"
		)
		(instances
			(project "OCuLink to 10GbE adapter"
				(path ""
					(reference "C25")
					(unit 1)
				)
			)
		)
	)
	(symbol
		(lib_id "antmicroResistors0402:R_0R_0402")
		(at 261.62 149.86 0)
		(unit 1)
		(exclude_from_sim no)
		(in_bom yes)
		(on_board yes)
		(dnp no)
		(property "Reference" "R24"
			(at 264.16 147.574 0)
			(effects
				(font
					(size 1.27 1.27)
					(thickness 0.15)
				)
			)
		)
		(property "Value" "R_0R_0402"
			(at 281.94 162.56 0)
			(effects
				(font
					(size 1.27 1.27)
					(thickness 0.15)
				)
				(justify left bottom)
				(hide yes)
			)
		)
		(property "Footprint" "antmicro-footprints:R_0402_1005Metric"
			(at 281.94 165.1 0)
			(effects
				(font
					(size 1.27 1.27)
					(thickness 0.15)
				)
				(justify left bottom)
				(hide yes)
			)
		)
		(property "Datasheet" "https://industrial.panasonic.com/cdbs/www-data/pdf/RDA0000/AOA0000C301.pdf"
			(at 281.94 167.64 0)
			(effects
				(font
					(size 1.27 1.27)
					(thickness 0.15)
				)
				(justify left bottom)
				(hide yes)
			)
		)
		(property "Description" "SMD Chip Resistor, Jumper, 0 ohm, 100 mW, 0402 [1005 Metric], Thick Film, General Purpose"
			(at 281.94 182.88 0)
			(effects
				(font
					(size 1.27 1.27)
				)
				(justify left bottom)
				(hide yes)
			)
		)
		(property "MPN" "ERJ2GE0R00X"
			(at 281.94 170.18 0)
			(effects
				(font
					(size 1.27 1.27)
					(thickness 0.15)
				)
				(justify left bottom)
				(hide yes)
			)
		)
		(property "Manufacturer" "Panasonic"
			(at 281.94 172.72 0)
			(effects
				(font
					(size 1.27 1.27)
					(thickness 0.15)
				)
				(justify left bottom)
				(hide yes)
			)
		)
		(property "License" "Apache-2.0"
			(at 281.94 175.26 0)
			(effects
				(font
					(size 1.27 1.27)
					(thickness 0.15)
				)
				(justify left bottom)
				(hide yes)
			)
		)
		(property "Author" "Antmicro"
			(at 281.94 177.8 0)
			(effects
				(font
					(size 1.27 1.27)
					(thickness 0.15)
				)
				(justify left bottom)
				(hide yes)
			)
		)
		(property "Val" "0R"
			(at 264.16 152.146 0)
			(effects
				(font
					(size 1.27 1.27)
					(thickness 0.15)
				)
			)
		)
		(property "Tolerance" "~"
			(at 281.94 160.02 0)
			(effects
				(font
					(size 1.27 1.27)
				)
				(justify left bottom)
				(hide yes)
			)
		)
		(property "Current" "1A"
			(at 281.94 180.34 0)
			(effects
				(font
					(size 1.27 1.27)
					(thickness 0.15)
				)
				(justify left bottom)
				(hide yes)
			)
		)
		(pin "2"
		)
		(pin "1"
		)
		(instances
			(project "OCuLink to 10GbE adapter"
				(path ""
					(reference "R24")
					(unit 1)
				)
			)
		)
	)
	(symbol
		(lib_id "antmicroCapacitors0603:C_22u_16V_0603")
		(at 217.17 190.5 270)
		(mirror x)
		(unit 1)
		(exclude_from_sim no)
		(in_bom yes)
		(on_board yes)
		(dnp no)
		(property "Reference" "C40"
			(at 215.138 186.69 90)
			(effects
				(font
					(size 1.27 1.27)
					(thickness 0.15)
				)
				(justify right)
			)
		)
		(property "Value" "C_22u_16V_0603"
			(at 207.01 170.18 0)
			(effects
				(font
					(size 1.27 1.27)
					(thickness 0.15)
				)
				(justify left bottom)
				(hide yes)
			)
		)
		(property "Footprint" "antmicro-footprints:C_0603_1608Metric_EIA"
			(at 204.47 170.18 0)
			(effects
				(font
					(size 1.27 1.27)
					(thickness 0.15)
				)
				(justify left bottom)
				(hide yes)
			)
		)
		(property "Datasheet" "https://product.samsungsem.com/mlcc/CL10A226MO7JZN.do"
			(at 201.93 170.18 0)
			(effects
				(font
					(size 1.27 1.27)
					(thickness 0.15)
				)
				(justify left bottom)
				(hide yes)
			)
		)
		(property "Description" "SMD Multilayer Ceramic Capacitor"
			(at 217.17 190.5 0)
			(effects
				(font
					(size 1.27 1.27)
				)
				(hide yes)
			)
		)
		(property "MPN" "CL10A226MO7JZNC"
			(at 199.39 170.18 0)
			(effects
				(font
					(size 1.27 1.27)
					(thickness 0.15)
				)
				(justify left bottom)
				(hide yes)
			)
		)
		(property "Manufacturer" "Samsung Electro-Mechanics"
			(at 196.85 170.18 0)
			(effects
				(font
					(size 1.27 1.27)
					(thickness 0.15)
				)
				(justify left bottom)
				(hide yes)
			)
		)
		(property "License" "Apache-2.0"
			(at 194.31 170.18 0)
			(effects
				(font
					(size 1.27 1.27)
					(thickness 0.15)
				)
				(justify left bottom)
				(hide yes)
			)
		)
		(property "Author" "Antmicro"
			(at 191.77 170.18 0)
			(effects
				(font
					(size 1.27 1.27)
					(thickness 0.15)
				)
				(justify left bottom)
				(hide yes)
			)
		)
		(property "Val" "22u"
			(at 215.138 189.23 90)
			(effects
				(font
					(size 1.27 1.27)
					(thickness 0.15)
				)
				(justify right)
			)
		)
		(property "Voltage" "16V"
			(at 214.63 190.4935 90)
			(effects
				(font
					(size 1.27 1.27)
				)
				(justify right)
				(hide yes)
			)
		)
		(property "Dielectric" ""
			(at 186.69 170.18 0)
			(effects
				(font
					(size 1.27 1.27)
				)
				(justify left bottom)
				(hide yes)
			)
		)
		(property "Public" "False"
			(at 184.15 170.18 0)
			(effects
				(font
					(size 1.27 1.27)
				)
				(justify left bottom)
				(hide yes)
			)
		)
		(pin "2"
		)
		(pin "1"
		)
		(instances
			(project "OCuLink to 10GbE adapter"
				(path ""
					(reference "C40")
					(unit 1)
				)
			)
		)
	)
	(symbol
		(lib_id "antmicroTestPoints:TP_1mm_SMD")
		(at 391.16 231.14 0)
		(unit 1)
		(exclude_from_sim no)
		(in_bom no)
		(on_board yes)
		(dnp no)
		(fields_autoplaced yes)
		(property "Reference" "TP31"
			(at 396.24 231.14 0)
			(effects
				(font
					(size 1.27 1.27)
					(thickness 0.15)
				)
				(justify left)
			)
		)
		(property "Value" "TP_1mm_SMD"
			(at 406.4 238.76 0)
			(effects
				(font
					(size 1.27 1.27)
					(thickness 0.15)
				)
				(justify left bottom)
				(hide yes)
			)
		)
		(property "Footprint" "antmicro-footprints:TP_SMD_1mm"
			(at 406.4 241.3 0)
			(effects
				(font
					(size 1.27 1.27)
					(thickness 0.15)
				)
				(justify left bottom)
				(hide yes)
			)
		)
		(property "Datasheet" ""
			(at 408.94 243.84 0)
			(effects
				(font
					(size 1.27 1.27)
					(thickness 0.15)
				)
				(justify left bottom)
				(hide yes)
			)
		)
		(property "Description" "Test point 1mm SMD"
			(at 406.4 251.46 0)
			(effects
				(font
					(size 1.27 1.27)
				)
				(justify left bottom)
				(hide yes)
			)
		)
		(property "MPN" ""
			(at 391.16 231.14 0)
			(effects
				(font
					(size 1.27 1.27)
				)
				(hide yes)
			)
		)
		(property "Manufacturer" ""
			(at 391.16 231.14 0)
			(effects
				(font
					(size 1.27 1.27)
				)
				(hide yes)
			)
		)
		(property "Author" "Antmicro"
			(at 406.4 246.38 0)
			(effects
				(font
					(size 1.27 1.27)
					(thickness 0.15)
				)
				(justify left bottom)
				(hide yes)
			)
		)
		(property "License" "Apache-2.0"
			(at 406.4 248.92 0)
			(effects
				(font
					(size 1.27 1.27)
					(thickness 0.15)
				)
				(justify left bottom)
				(hide yes)
			)
		)
		(pin "1"
		)
		(instances
			(project "oculink-to-10gbe-adapter"
				(path ""
					(reference "TP31")
					(unit 1)
				)
			)
		)
	)
	(symbol
		(lib_id "antmicroResistors0603:R_0R_22.4A_0603")
		(at 379.73 139.7 0)
		(unit 1)
		(exclude_from_sim no)
		(in_bom yes)
		(on_board yes)
		(dnp no)
		(property "Reference" "R19"
			(at 379.73 138.43 0)
			(effects
				(font
					(size 1.27 1.27)
					(thickness 0.15)
				)
				(justify right)
			)
		)
		(property "Value" "R_0R_22.4A_0603"
			(at 394.97 144.78 0)
			(effects
				(font
					(size 1.27 1.27)
					(thickness 0.15)
				)
				(justify left bottom)
				(hide yes)
			)
		)
		(property "Footprint" "antmicro-footprints:R_0603_1608Metric"
			(at 394.97 149.86 0)
			(effects
				(font
					(size 1.27 1.27)
					(thickness 0.15)
				)
				(justify left bottom)
				(hide yes)
			)
		)
		(property "Datasheet" "https://fscdn.rohm.com/en/products/databook/datasheet/passive/resistor/chip_resistor/pmr-jpw-e.pdf"
			(at 394.97 152.4 0)
			(effects
				(font
					(size 1.27 1.27)
					(thickness 0.15)
				)
				(justify left bottom)
				(hide yes)
			)
		)
		(property "Description" "SMD Chip Resistor"
			(at 394.97 167.64 0)
			(effects
				(font
					(size 1.27 1.27)
				)
				(justify left bottom)
				(hide yes)
			)
		)
		(property "MPN" "PMR03EZPJ000"
			(at 394.97 154.94 0)
			(effects
				(font
					(size 1.27 1.27)
					(thickness 0.15)
				)
				(justify left bottom)
				(hide yes)
			)
		)
		(property "Manufacturer" "ROHM Semiconductor"
			(at 394.97 157.48 0)
			(effects
				(font
					(size 1.27 1.27)
					(thickness 0.15)
				)
				(justify left bottom)
				(hide yes)
			)
		)
		(property "Val" "0R"
			(at 384.81 138.43 0)
			(effects
				(font
					(size 1.27 1.27)
					(thickness 0.15)
				)
				(justify left)
			)
		)
		(property "Max. Curr." "22.4A"
			(at 382.27 142.24 0)
			(effects
				(font
					(size 1.27 1.27)
					(thickness 0.15)
				)
			)
		)
		(property "Author" "Antmicro"
			(at 394.97 162.56 0)
			(effects
				(font
					(size 1.27 1.27)
					(thickness 0.15)
				)
				(justify left bottom)
				(hide yes)
			)
		)
		(property "License" "Apache-2.0"
			(at 394.97 165.1 0)
			(effects
				(font
					(size 1.27 1.27)
					(thickness 0.15)
				)
				(justify left bottom)
				(hide yes)
			)
		)
		(property "Tolerance" "template_tolerance"
			(at 400.05 149.86 0)
			(effects
				(font
					(size 1.27 1.27)
				)
				(justify left bottom)
				(hide yes)
			)
		)
		(pin "1"
		)
		(pin "2"
		)
		(instances
			(project "OCuLink to 10GbE adapter"
				(path ""
					(reference "R19")
					(unit 1)
				)
			)
		)
	)
	(symbol
		(lib_id "antmicropower:GND")
		(at 247.65 119.38 0)
		(unit 1)
		(exclude_from_sim no)
		(in_bom yes)
		(on_board yes)
		(dnp no)
		(property "Reference" "#PWR030"
			(at 256.54 121.92 0)
			(effects
				(font
					(size 1.27 1.27)
					(thickness 0.15)
				)
				(justify left bottom)
				(hide yes)
			)
		)
		(property "Value" "GND"
			(at 247.65 123.19 0)
			(effects
				(font
					(size 1.27 1.27)
					(thickness 0.15)
				)
			)
		)
		(property "Footprint" ""
			(at 256.54 127 0)
			(effects
				(font
					(size 1.27 1.27)
					(thickness 0.15)
				)
				(justify left bottom)
				(hide yes)
			)
		)
		(property "Datasheet" ""
			(at 256.54 132.08 0)
			(effects
				(font
					(size 1.27 1.27)
					(thickness 0.15)
				)
				(justify left bottom)
				(hide yes)
			)
		)
		(property "Description" ""
			(at 247.65 119.38 0)
			(effects
				(font
					(size 1.27 1.27)
				)
				(hide yes)
			)
		)
		(property "Author" "Antmicro"
			(at 256.54 127 0)
			(effects
				(font
					(size 1.27 1.27)
					(thickness 0.15)
				)
				(justify left bottom)
				(hide yes)
			)
		)
		(property "License" "Apache-2.0"
			(at 256.54 129.54 0)
			(effects
				(font
					(size 1.27 1.27)
					(thickness 0.15)
				)
				(justify left bottom)
				(hide yes)
			)
		)
		(pin "1"
		)
		(instances
			(project "OCuLink to 10GbE adapter"
				(path ""
					(reference "#PWR030")
					(unit 1)
				)
			)
		)
	)
	(symbol
		(lib_id "antmicropower:GND")
		(at 227.33 43.18 0)
		(unit 1)
		(exclude_from_sim no)
		(in_bom yes)
		(on_board yes)
		(dnp no)
		(property "Reference" "#PWR05"
			(at 236.22 45.72 0)
			(effects
				(font
					(size 1.27 1.27)
					(thickness 0.15)
				)
				(justify left bottom)
				(hide yes)
			)
		)
		(property "Value" "GND"
			(at 227.33 46.99 0)
			(effects
				(font
					(size 1.27 1.27)
					(thickness 0.15)
				)
			)
		)
		(property "Footprint" ""
			(at 236.22 50.8 0)
			(effects
				(font
					(size 1.27 1.27)
					(thickness 0.15)
				)
				(justify left bottom)
				(hide yes)
			)
		)
		(property "Datasheet" ""
			(at 236.22 55.88 0)
			(effects
				(font
					(size 1.27 1.27)
					(thickness 0.15)
				)
				(justify left bottom)
				(hide yes)
			)
		)
		(property "Description" ""
			(at 227.33 43.18 0)
			(effects
				(font
					(size 1.27 1.27)
				)
				(hide yes)
			)
		)
		(property "Author" "Antmicro"
			(at 236.22 50.8 0)
			(effects
				(font
					(size 1.27 1.27)
					(thickness 0.15)
				)
				(justify left bottom)
				(hide yes)
			)
		)
		(property "License" "Apache-2.0"
			(at 236.22 53.34 0)
			(effects
				(font
					(size 1.27 1.27)
					(thickness 0.15)
				)
				(justify left bottom)
				(hide yes)
			)
		)
		(pin "1"
		)
		(instances
			(project "OCuLink to 10GbE adapter"
				(path ""
					(reference "#PWR05")
					(unit 1)
				)
			)
		)
	)
	(symbol
		(lib_id "antmicroTestPoints:TP_0.75mm_SMD")
		(at 64.77 83.82 90)
		(unit 1)
		(exclude_from_sim no)
		(in_bom no)
		(on_board yes)
		(dnp no)
		(property "Reference" "TP23"
			(at 64.77 78.74 90)
			(effects
				(font
					(size 1.27 1.27)
					(thickness 0.15)
				)
			)
		)
		(property "Value" "TP_0.75mm_SMD"
			(at 68.58 73.66 0)
			(effects
				(font
					(size 1.27 1.27)
					(thickness 0.15)
				)
				(justify left bottom)
				(hide yes)
			)
		)
		(property "Footprint" "antmicro-footprints:TP_SMD_0.75mm"
			(at 71.12 73.66 0)
			(effects
				(font
					(size 1.27 1.27)
					(thickness 0.15)
				)
				(justify left bottom)
				(hide yes)
			)
		)
		(property "Datasheet" ""
			(at 77.47 66.04 0)
			(effects
				(font
					(size 1.27 1.27)
					(thickness 0.15)
				)
				(justify left bottom)
				(hide yes)
			)
		)
		(property "Description" "SMT test point"
			(at 64.77 83.82 0)
			(effects
				(font
					(size 1.27 1.27)
				)
				(hide yes)
			)
		)
		(property "MPN" ""
			(at 76.2 73.025 0)
			(effects
				(font
					(size 1.27 1.27)
					(thickness 0.15)
				)
				(justify left bottom)
				(hide yes)
			)
		)
		(property "Manufacturer" ""
			(at 71.12 73.025 0)
			(effects
				(font
					(size 1.27 1.27)
					(thickness 0.15)
				)
				(justify left bottom)
				(hide yes)
			)
		)
		(property "Author" "Antmicro"
			(at 73.66 73.66 0)
			(effects
				(font
					(size 1.27 1.27)
					(thickness 0.15)
				)
				(justify left bottom)
				(hide yes)
			)
		)
		(property "License" "Apache-2.0"
			(at 76.2 73.66 0)
			(effects
				(font
					(size 1.27 1.27)
					(thickness 0.15)
				)
				(justify left bottom)
				(hide yes)
			)
		)
		(pin "1"
		)
		(instances
			(project "OCuLink to 10GbE adapter"
				(path ""
					(reference "TP23")
					(unit 1)
				)
			)
		)
	)
	(symbol
		(lib_id "antmicropower:VCC")
		(at 143.51 82.55 0)
		(unit 1)
		(exclude_from_sim no)
		(in_bom yes)
		(on_board yes)
		(dnp no)
		(property "Reference" "#PWR0352"
			(at 143.51 86.36 0)
			(effects
				(font
					(size 1.27 1.27)
				)
				(hide yes)
			)
		)
		(property "Value" "VCC"
			(at 143.51 78.74 0)
			(effects
				(font
					(size 1.27 1.27)
				)
			)
		)
		(property "Footprint" ""
			(at 143.51 82.55 0)
			(effects
				(font
					(size 1.27 1.27)
				)
				(hide yes)
			)
		)
		(property "Datasheet" ""
			(at 143.51 82.55 0)
			(effects
				(font
					(size 1.27 1.27)
				)
				(hide yes)
			)
		)
		(property "Description" ""
			(at 143.51 88.9 0)
			(effects
				(font
					(size 1.27 1.27)
				)
				(justify left bottom)
				(hide yes)
			)
		)
		(pin "1"
		)
		(instances
			(project ""
				(path ""
					(reference "#PWR0352")
					(unit 1)
				)
			)
		)
	)
	(symbol
		(lib_id "antmicroCapacitors0402:C_100n_0402")
		(at 237.49 114.3 270)
		(mirror x)
		(unit 1)
		(exclude_from_sim no)
		(in_bom yes)
		(on_board yes)
		(dnp no)
		(property "Reference" "C23"
			(at 235.712 110.49 90)
			(effects
				(font
					(size 1.27 1.27)
					(thickness 0.15)
				)
				(justify right)
			)
		)
		(property "Value" "C_100n_0402"
			(at 227.33 93.98 0)
			(effects
				(font
					(size 1.27 1.27)
					(thickness 0.15)
				)
				(justify left bottom)
				(hide yes)
			)
		)
		(property "Footprint" "antmicro-footprints:C_0402_1005Metric"
			(at 224.79 93.98 0)
			(effects
				(font
					(size 1.27 1.27)
					(thickness 0.15)
				)
				(justify left bottom)
				(hide yes)
			)
		)
		(property "Datasheet" "https://www.murata.com/products/productdetail?partno=GRM155R61H104KE14%23"
			(at 222.25 93.98 0)
			(effects
				(font
					(size 1.27 1.27)
					(thickness 0.15)
				)
				(justify left bottom)
				(hide yes)
			)
		)
		(property "Description" "SMD Multilayer Ceramic Capacitor, 0.1 µF, 50 V, 0402 [1005 Metric], ± 10%, X5R, GRM Series"
			(at 204.47 93.98 0)
			(effects
				(font
					(size 1.27 1.27)
				)
				(justify left bottom)
				(hide yes)
			)
		)
		(property "MPN" "GRM155R61H104KE14D"
			(at 219.71 93.98 0)
			(effects
				(font
					(size 1.27 1.27)
					(thickness 0.15)
				)
				(justify left bottom)
				(hide yes)
			)
		)
		(property "Manufacturer" "Murata"
			(at 217.17 93.98 0)
			(effects
				(font
					(size 1.27 1.27)
					(thickness 0.15)
				)
				(justify left bottom)
				(hide yes)
			)
		)
		(property "License" "Apache-2.0"
			(at 214.63 93.98 0)
			(effects
				(font
					(size 1.27 1.27)
					(thickness 0.15)
				)
				(justify left bottom)
				(hide yes)
			)
		)
		(property "Author" "Antmicro"
			(at 212.09 93.98 0)
			(effects
				(font
					(size 1.27 1.27)
					(thickness 0.15)
				)
				(justify left bottom)
				(hide yes)
			)
		)
		(property "Val" "100n"
			(at 235.712 113.03 90)
			(effects
				(font
					(size 1.27 1.27)
					(thickness 0.15)
				)
				(justify right)
			)
		)
		(property "Voltage" "50V"
			(at 209.55 93.98 0)
			(effects
				(font
					(size 1.27 1.27)
				)
				(justify left bottom)
				(hide yes)
			)
		)
		(property "Dielectric" "X5R"
			(at 207.01 93.98 0)
			(effects
				(font
					(size 1.27 1.27)
				)
				(justify left bottom)
				(hide yes)
			)
		)
		(pin "1"
		)
		(pin "2"
		)
		(instances
			(project "OCuLink to 10GbE adapter"
				(path ""
					(reference "C23")
					(unit 1)
				)
			)
		)
	)
	(symbol
		(lib_id "antmicropower:GND")
		(at 101.6 172.72 0)
		(unit 1)
		(exclude_from_sim no)
		(in_bom yes)
		(on_board yes)
		(dnp no)
		(property "Reference" "#PWR051"
			(at 110.49 175.26 0)
			(effects
				(font
					(size 1.27 1.27)
					(thickness 0.15)
				)
				(justify left bottom)
				(hide yes)
			)
		)
		(property "Value" "GND"
			(at 101.6 176.53 0)
			(effects
				(font
					(size 1.27 1.27)
					(thickness 0.15)
				)
			)
		)
		(property "Footprint" ""
			(at 110.49 180.34 0)
			(effects
				(font
					(size 1.27 1.27)
					(thickness 0.15)
				)
				(justify left bottom)
				(hide yes)
			)
		)
		(property "Datasheet" ""
			(at 110.49 185.42 0)
			(effects
				(font
					(size 1.27 1.27)
					(thickness 0.15)
				)
				(justify left bottom)
				(hide yes)
			)
		)
		(property "Description" ""
			(at 101.6 172.72 0)
			(effects
				(font
					(size 1.27 1.27)
				)
				(hide yes)
			)
		)
		(property "Author" "Antmicro"
			(at 110.49 180.34 0)
			(effects
				(font
					(size 1.27 1.27)
					(thickness 0.15)
				)
				(justify left bottom)
				(hide yes)
			)
		)
		(property "License" "Apache-2.0"
			(at 110.49 182.88 0)
			(effects
				(font
					(size 1.27 1.27)
					(thickness 0.15)
				)
				(justify left bottom)
				(hide yes)
			)
		)
		(pin "1"
		)
		(instances
			(project "OCuLink to 10GbE adapter"
				(path ""
					(reference "#PWR051")
					(unit 1)
				)
			)
		)
	)
	(symbol
		(lib_id "antmicroCapacitors0603:C_22u_16V_0603")
		(at 354.33 114.3 90)
		(unit 1)
		(exclude_from_sim no)
		(in_bom yes)
		(on_board yes)
		(dnp no)
		(property "Reference" "C26"
			(at 356.108 110.49 90)
			(effects
				(font
					(size 1.27 1.27)
					(thickness 0.15)
				)
				(justify right)
			)
		)
		(property "Value" "C_22u_16V_0603"
			(at 364.49 93.98 0)
			(effects
				(font
					(size 1.27 1.27)
					(thickness 0.15)
				)
				(justify left bottom)
				(hide yes)
			)
		)
		(property "Footprint" "antmicro-footprints:C_0603_1608Metric_EIA"
			(at 367.03 93.98 0)
			(effects
				(font
					(size 1.27 1.27)
					(thickness 0.15)
				)
				(justify left bottom)
				(hide yes)
			)
		)
		(property "Datasheet" "https://product.samsungsem.com/mlcc/CL10A226MO7JZN.do"
			(at 369.57 93.98 0)
			(effects
				(font
					(size 1.27 1.27)
					(thickness 0.15)
				)
				(justify left bottom)
				(hide yes)
			)
		)
		(property "Description" "SMD Multilayer Ceramic Capacitor"
			(at 354.33 114.3 0)
			(effects
				(font
					(size 1.27 1.27)
				)
				(hide yes)
			)
		)
		(property "MPN" "CL10A226MO7JZNC"
			(at 372.11 93.98 0)
			(effects
				(font
					(size 1.27 1.27)
					(thickness 0.15)
				)
				(justify left bottom)
				(hide yes)
			)
		)
		(property "Manufacturer" "Samsung Electro-Mechanics"
			(at 374.65 93.98 0)
			(effects
				(font
					(size 1.27 1.27)
					(thickness 0.15)
				)
				(justify left bottom)
				(hide yes)
			)
		)
		(property "License" "Apache-2.0"
			(at 377.19 93.98 0)
			(effects
				(font
					(size 1.27 1.27)
					(thickness 0.15)
				)
				(justify left bottom)
				(hide yes)
			)
		)
		(property "Author" "Antmicro"
			(at 379.73 93.98 0)
			(effects
				(font
					(size 1.27 1.27)
					(thickness 0.15)
				)
				(justify left bottom)
				(hide yes)
			)
		)
		(property "Val" "22u"
			(at 356.108 113.03 90)
			(effects
				(font
					(size 1.27 1.27)
					(thickness 0.15)
				)
				(justify right)
			)
		)
		(property "Voltage" "16V"
			(at 356.87 114.2935 90)
			(effects
				(font
					(size 1.27 1.27)
				)
				(justify right)
				(hide yes)
			)
		)
		(property "Dielectric" ""
			(at 384.81 93.98 0)
			(effects
				(font
					(size 1.27 1.27)
				)
				(justify left bottom)
				(hide yes)
			)
		)
		(property "Public" "False"
			(at 387.35 93.98 0)
			(effects
				(font
					(size 1.27 1.27)
				)
				(justify left bottom)
				(hide yes)
			)
		)
		(pin "2"
		)
		(pin "1"
		)
		(instances
			(project "OCuLink to 10GbE adapter"
				(path ""
					(reference "C26")
					(unit 1)
				)
			)
		)
	)
	(symbol
		(lib_id "antmicroTestPoints:TP_0.75mm_SMD")
		(at 350.52 100.33 90)
		(unit 1)
		(exclude_from_sim no)
		(in_bom no)
		(on_board yes)
		(dnp no)
		(property "Reference" "TP39"
			(at 350.52 95.25 90)
			(effects
				(font
					(size 1.27 1.27)
					(thickness 0.15)
				)
			)
		)
		(property "Value" "TP_0.75mm_SMD"
			(at 354.33 90.17 0)
			(effects
				(font
					(size 1.27 1.27)
					(thickness 0.15)
				)
				(justify left bottom)
				(hide yes)
			)
		)
		(property "Footprint" "antmicro-footprints:TP_SMD_0.75mm"
			(at 356.87 90.17 0)
			(effects
				(font
					(size 1.27 1.27)
					(thickness 0.15)
				)
				(justify left bottom)
				(hide yes)
			)
		)
		(property "Datasheet" ""
			(at 363.22 82.55 0)
			(effects
				(font
					(size 1.27 1.27)
					(thickness 0.15)
				)
				(justify left bottom)
				(hide yes)
			)
		)
		(property "Description" "SMT test point"
			(at 350.52 100.33 0)
			(effects
				(font
					(size 1.27 1.27)
				)
				(hide yes)
			)
		)
		(property "MPN" ""
			(at 361.95 89.535 0)
			(effects
				(font
					(size 1.27 1.27)
					(thickness 0.15)
				)
				(justify left bottom)
				(hide yes)
			)
		)
		(property "Manufacturer" ""
			(at 356.87 89.535 0)
			(effects
				(font
					(size 1.27 1.27)
					(thickness 0.15)
				)
				(justify left bottom)
				(hide yes)
			)
		)
		(property "Author" "Antmicro"
			(at 359.41 90.17 0)
			(effects
				(font
					(size 1.27 1.27)
					(thickness 0.15)
				)
				(justify left bottom)
				(hide yes)
			)
		)
		(property "License" "Apache-2.0"
			(at 361.95 90.17 0)
			(effects
				(font
					(size 1.27 1.27)
					(thickness 0.15)
				)
				(justify left bottom)
				(hide yes)
			)
		)
		(pin "1"
		)
		(instances
			(project "oculink-to-10gbe-adapter"
				(path ""
					(reference "TP39")
					(unit 1)
				)
			)
		)
	)
	(symbol
		(lib_id "antmicroLEDIndicationDiscrete:LED_G_0603_LG_L29K-G2J1-24-Z")
		(at 254 223.52 90)
		(unit 1)
		(exclude_from_sim no)
		(in_bom yes)
		(on_board yes)
		(dnp no)
		(property "Reference" "D19"
			(at 255.27 219.71 90)
			(effects
				(font
					(size 1.27 1.27)
					(thickness 0.15)
				)
				(justify right)
			)
		)
		(property "Value" "LED_G_0603_LG_L29K-G2J1-24-Z"
			(at 261.62 203.2 0)
			(effects
				(font
					(size 1.27 1.27)
					(thickness 0.15)
				)
				(justify left bottom)
				(hide yes)
			)
		)
		(property "Footprint" "antmicro-footprints:LED_0603_1608Metric_G"
			(at 264.16 203.2 0)
			(effects
				(font
					(size 1.27 1.27)
					(thickness 0.15)
				)
				(justify left bottom)
				(hide yes)
			)
		)
		(property "Datasheet" "https://look.ams-osram.com/m/19ee86b3ae0ee95b/original/LG-L29K.pdf"
			(at 266.7 203.2 0)
			(effects
				(font
					(size 1.27 1.27)
					(thickness 0.15)
				)
				(justify left bottom)
				(hide yes)
			)
		)
		(property "Description" "LED, Green, SMD, 0603, 20 mA, 1.7 V, 570 nm"
			(at 254 223.52 0)
			(effects
				(font
					(size 1.27 1.27)
				)
				(hide yes)
			)
		)
		(property "MPN" "LG L29K-G2J1-24-Z"
			(at 269.24 203.2 0)
			(effects
				(font
					(size 1.27 1.27)
					(thickness 0.15)
				)
				(justify left bottom)
				(hide yes)
			)
		)
		(property "Manufacturer" "OSRAM"
			(at 271.78 203.2 0)
			(effects
				(font
					(size 1.27 1.27)
					(thickness 0.15)
				)
				(justify left bottom)
				(hide yes)
			)
		)
		(property "Color" "Green"
			(at 255.27 222.2499 90)
			(effects
				(font
					(size 1.27 1.27)
				)
				(justify right)
			)
		)
		(property "Author" "Antmicro"
			(at 274.32 203.2 0)
			(effects
				(font
					(size 1.27 1.27)
					(thickness 0.15)
				)
				(justify left bottom)
				(hide yes)
			)
		)
		(property "License" "Apache-2.0"
			(at 276.86 203.2 0)
			(effects
				(font
					(size 1.27 1.27)
					(thickness 0.15)
				)
				(justify left bottom)
				(hide yes)
			)
		)
		(pin "2"
		)
		(pin "1"
		)
		(instances
			(project "oculink-to-10gbe-adapter"
				(path ""
					(reference "D19")
					(unit 1)
				)
			)
		)
	)
	(symbol
		(lib_id "antmicropower:PWR_FLAG")
		(at 391.16 137.16 0)
		(unit 1)
		(exclude_from_sim no)
		(in_bom yes)
		(on_board yes)
		(dnp no)
		(property "Reference" "#FLG07"
			(at 391.16 135.255 0)
			(effects
				(font
					(size 1.27 1.27)
				)
				(hide yes)
			)
		)
		(property "Value" "PWR_FLAG"
			(at 391.16 133.35 0)
			(effects
				(font
					(size 1.27 1.27)
				)
			)
		)
		(property "Footprint" ""
			(at 391.16 137.16 0)
			(effects
				(font
					(size 1.27 1.27)
				)
				(hide yes)
			)
		)
		(property "Datasheet" ""
			(at 391.16 137.16 0)
			(effects
				(font
					(size 1.27 1.27)
				)
				(hide yes)
			)
		)
		(property "Description" ""
			(at 391.16 137.16 0)
			(effects
				(font
					(size 1.27 1.27)
				)
				(hide yes)
			)
		)
		(pin "1"
		)
		(instances
			(project "OCuLink to 10GbE adapter"
				(path ""
					(reference "#FLG07")
					(unit 1)
				)
			)
		)
	)
	(symbol
		(lib_id "antmicropower:GND")
		(at 346.71 246.38 0)
		(unit 1)
		(exclude_from_sim no)
		(in_bom yes)
		(on_board yes)
		(dnp no)
		(property "Reference" "#PWR062"
			(at 355.6 248.92 0)
			(effects
				(font
					(size 1.27 1.27)
					(thickness 0.15)
				)
				(justify left bottom)
				(hide yes)
			)
		)
		(property "Value" "GND"
			(at 346.71 250.19 0)
			(effects
				(font
					(size 1.27 1.27)
					(thickness 0.15)
				)
			)
		)
		(property "Footprint" ""
			(at 355.6 254 0)
			(effects
				(font
					(size 1.27 1.27)
					(thickness 0.15)
				)
				(justify left bottom)
				(hide yes)
			)
		)
		(property "Datasheet" ""
			(at 355.6 259.08 0)
			(effects
				(font
					(size 1.27 1.27)
					(thickness 0.15)
				)
				(justify left bottom)
				(hide yes)
			)
		)
		(property "Description" ""
			(at 346.71 246.38 0)
			(effects
				(font
					(size 1.27 1.27)
				)
				(hide yes)
			)
		)
		(property "Author" "Antmicro"
			(at 355.6 254 0)
			(effects
				(font
					(size 1.27 1.27)
					(thickness 0.15)
				)
				(justify left bottom)
				(hide yes)
			)
		)
		(property "License" "Apache-2.0"
			(at 355.6 256.54 0)
			(effects
				(font
					(size 1.27 1.27)
					(thickness 0.15)
				)
				(justify left bottom)
				(hide yes)
			)
		)
		(pin "1"
		)
		(instances
			(project "OCuLink to 10GbE adapter"
				(path ""
					(reference "#PWR062")
					(unit 1)
				)
			)
		)
	)
	(symbol
		(lib_id "antmicropower:GND")
		(at 374.65 157.48 0)
		(unit 1)
		(exclude_from_sim no)
		(in_bom yes)
		(on_board yes)
		(dnp no)
		(property "Reference" "#PWR045"
			(at 383.54 160.02 0)
			(effects
				(font
					(size 1.27 1.27)
					(thickness 0.15)
				)
				(justify left bottom)
				(hide yes)
			)
		)
		(property "Value" "GND"
			(at 374.65 161.29 0)
			(effects
				(font
					(size 1.27 1.27)
					(thickness 0.15)
				)
			)
		)
		(property "Footprint" ""
			(at 383.54 165.1 0)
			(effects
				(font
					(size 1.27 1.27)
					(thickness 0.15)
				)
				(justify left bottom)
				(hide yes)
			)
		)
		(property "Datasheet" ""
			(at 383.54 170.18 0)
			(effects
				(font
					(size 1.27 1.27)
					(thickness 0.15)
				)
				(justify left bottom)
				(hide yes)
			)
		)
		(property "Description" ""
			(at 374.65 157.48 0)
			(effects
				(font
					(size 1.27 1.27)
				)
				(hide yes)
			)
		)
		(property "Author" "Antmicro"
			(at 383.54 165.1 0)
			(effects
				(font
					(size 1.27 1.27)
					(thickness 0.15)
				)
				(justify left bottom)
				(hide yes)
			)
		)
		(property "License" "Apache-2.0"
			(at 383.54 167.64 0)
			(effects
				(font
					(size 1.27 1.27)
					(thickness 0.15)
				)
				(justify left bottom)
				(hide yes)
			)
		)
		(pin "1"
		)
		(instances
			(project "OCuLink to 10GbE adapter"
				(path ""
					(reference "#PWR045")
					(unit 1)
				)
			)
		)
	)
	(symbol
		(lib_id "antmicroCapacitors0402:C_100n_0402")
		(at 53.34 167.64 90)
		(unit 1)
		(exclude_from_sim no)
		(in_bom yes)
		(on_board yes)
		(dnp no)
		(property "Reference" "C37"
			(at 55.118 163.83 90)
			(effects
				(font
					(size 1.27 1.27)
					(thickness 0.15)
				)
				(justify right)
			)
		)
		(property "Value" "C_100n_0402"
			(at 76.2 152.4 0)
			(effects
				(font
					(size 1.27 1.27)
					(thickness 0.15)
				)
				(justify left bottom)
				(hide yes)
			)
		)
		(property "Footprint" "antmicro-footprints:C_0402_1005Metric"
			(at 78.74 152.4 0)
			(effects
				(font
					(size 1.27 1.27)
					(thickness 0.15)
				)
				(justify left bottom)
				(hide yes)
			)
		)
		(property "Datasheet" "https://www.murata.com/products/productdetail?partno=GRM155R61H104KE14%23"
			(at 81.28 152.4 0)
			(effects
				(font
					(size 1.27 1.27)
					(thickness 0.15)
				)
				(justify left bottom)
				(hide yes)
			)
		)
		(property "Description" "SMD Multilayer Ceramic Capacitor, 0.1 µF, 50 V, 0402 [1005 Metric], ± 10%, X5R, GRM Series"
			(at 53.34 167.64 0)
			(effects
				(font
					(size 1.27 1.27)
				)
				(hide yes)
			)
		)
		(property "MPN" "GRM155R61H104KE14D"
			(at 83.82 152.4 0)
			(effects
				(font
					(size 1.27 1.27)
					(thickness 0.15)
				)
				(justify left bottom)
				(hide yes)
			)
		)
		(property "Val" "100n"
			(at 55.118 166.37 90)
			(effects
				(font
					(size 1.27 1.27)
					(thickness 0.15)
				)
				(justify right)
			)
		)
		(property "Voltage" "50V"
			(at 63.5 152.4 0)
			(effects
				(font
					(size 1.27 1.27)
					(thickness 0.15)
				)
				(justify left bottom)
				(hide yes)
			)
		)
		(property "Dielectric" "X5R"
			(at 66.04 152.4 0)
			(effects
				(font
					(size 1.27 1.27)
					(thickness 0.15)
				)
				(justify left bottom)
				(hide yes)
			)
		)
		(property "Manufacturer" "Murata"
			(at 68.58 152.4 0)
			(effects
				(font
					(size 1.27 1.27)
					(thickness 0.15)
				)
				(justify left bottom)
				(hide yes)
			)
		)
		(property "License" "Apache-2.0"
			(at 71.12 152.4 0)
			(effects
				(font
					(size 1.27 1.27)
					(thickness 0.15)
				)
				(justify left bottom)
				(hide yes)
			)
		)
		(property "Author" "Antmicro"
			(at 73.66 152.4 0)
			(effects
				(font
					(size 1.27 1.27)
					(thickness 0.15)
				)
				(justify left bottom)
				(hide yes)
			)
		)
		(pin "1"
		)
		(pin "2"
		)
		(instances
			(project ""
				(path ""
					(reference "C37")
					(unit 1)
				)
			)
		)
	)
	(symbol
		(lib_id "antmicroResistors0402:R_1k_0402")
		(at 304.8 220.98 90)
		(unit 1)
		(exclude_from_sim no)
		(in_bom yes)
		(on_board yes)
		(dnp no)
		(property "Reference" "R170"
			(at 306.07 217.17 90)
			(effects
				(font
					(size 1.27 1.27)
					(thickness 0.15)
				)
				(justify right)
			)
		)
		(property "Value" "R_1k_0402"
			(at 317.5 200.66 0)
			(effects
				(font
					(size 1.27 1.27)
					(thickness 0.15)
				)
				(justify left bottom)
				(hide yes)
			)
		)
		(property "Footprint" "antmicro-footprints:R_0402_1005Metric"
			(at 320.04 200.66 0)
			(effects
				(font
					(size 1.27 1.27)
					(thickness 0.15)
				)
				(justify left bottom)
				(hide yes)
			)
		)
		(property "Datasheet" "https://www.bourns.com/docs/product-datasheets/cr.pdf"
			(at 322.58 200.66 0)
			(effects
				(font
					(size 1.27 1.27)
					(thickness 0.15)
				)
				(justify left bottom)
				(hide yes)
			)
		)
		(property "Description" "SMD Chip Resistor, 1 kohm, ± 1%, 63 mW, 0402 [1005 Metric], Thick Film, General Purpose"
			(at 335.28 200.66 0)
			(effects
				(font
					(size 1.27 1.27)
				)
				(justify left bottom)
				(hide yes)
			)
		)
		(property "MPN" "CR0402-FX-1001GLF"
			(at 325.12 200.66 0)
			(effects
				(font
					(size 1.27 1.27)
					(thickness 0.15)
				)
				(justify left bottom)
				(hide yes)
			)
		)
		(property "Manufacturer" "Bourns"
			(at 327.66 200.66 0)
			(effects
				(font
					(size 1.27 1.27)
					(thickness 0.15)
				)
				(justify left bottom)
				(hide yes)
			)
		)
		(property "License" "Apache-2.0"
			(at 330.2 200.66 0)
			(effects
				(font
					(size 1.27 1.27)
					(thickness 0.15)
				)
				(justify left bottom)
				(hide yes)
			)
		)
		(property "Author" "Antmicro"
			(at 332.74 200.66 0)
			(effects
				(font
					(size 1.27 1.27)
					(thickness 0.15)
				)
				(justify left bottom)
				(hide yes)
			)
		)
		(property "Val" "1k"
			(at 306.07 219.71 90)
			(effects
				(font
					(size 1.27 1.27)
					(thickness 0.15)
				)
				(justify right)
			)
		)
		(property "Tolerance" "1%"
			(at 314.96 200.66 0)
			(effects
				(font
					(size 1.27 1.27)
				)
				(justify left bottom)
				(hide yes)
			)
		)
		(pin "1"
		)
		(pin "2"
		)
		(instances
			(project "oculink-to-10gbe-adapter"
				(path ""
					(reference "R170")
					(unit 1)
				)
			)
		)
	)
	(symbol
		(lib_id "antmicroCapacitors0402:C_100n_0402")
		(at 307.34 68.58 270)
		(mirror x)
		(unit 1)
		(exclude_from_sim no)
		(in_bom yes)
		(on_board yes)
		(dnp no)
		(property "Reference" "C10"
			(at 309.118 65.024 90)
			(effects
				(font
					(size 1.27 1.27)
					(thickness 0.15)
				)
				(justify left)
			)
		)
		(property "Value" "C_100n_0402"
			(at 297.18 48.26 0)
			(effects
				(font
					(size 1.27 1.27)
					(thickness 0.15)
				)
				(justify left bottom)
				(hide yes)
			)
		)
		(property "Footprint" "antmicro-footprints:C_0402_1005Metric"
			(at 294.64 48.26 0)
			(effects
				(font
					(size 1.27 1.27)
					(thickness 0.15)
				)
				(justify left bottom)
				(hide yes)
			)
		)
		(property "Datasheet" "https://www.murata.com/products/productdetail?partno=GRM155R61H104KE14%23"
			(at 292.1 48.26 0)
			(effects
				(font
					(size 1.27 1.27)
					(thickness 0.15)
				)
				(justify left bottom)
				(hide yes)
			)
		)
		(property "Description" "SMD Multilayer Ceramic Capacitor, 0.1 µF, 50 V, 0402 [1005 Metric], ± 10%, X5R, GRM Series"
			(at 274.32 48.26 0)
			(effects
				(font
					(size 1.27 1.27)
				)
				(justify left bottom)
				(hide yes)
			)
		)
		(property "MPN" "GRM155R61H104KE14D"
			(at 289.56 48.26 0)
			(effects
				(font
					(size 1.27 1.27)
					(thickness 0.15)
				)
				(justify left bottom)
				(hide yes)
			)
		)
		(property "Manufacturer" "Murata"
			(at 287.02 48.26 0)
			(effects
				(font
					(size 1.27 1.27)
					(thickness 0.15)
				)
				(justify left bottom)
				(hide yes)
			)
		)
		(property "License" "Apache-2.0"
			(at 284.48 48.26 0)
			(effects
				(font
					(size 1.27 1.27)
					(thickness 0.15)
				)
				(justify left bottom)
				(hide yes)
			)
		)
		(property "Author" "Antmicro"
			(at 281.94 48.26 0)
			(effects
				(font
					(size 1.27 1.27)
					(thickness 0.15)
				)
				(justify left bottom)
				(hide yes)
			)
		)
		(property "Val" "100n"
			(at 309.118 67.564 90)
			(effects
				(font
					(size 1.27 1.27)
					(thickness 0.15)
				)
				(justify left)
			)
		)
		(property "Voltage" "50V"
			(at 279.4 48.26 0)
			(effects
				(font
					(size 1.27 1.27)
				)
				(justify left bottom)
				(hide yes)
			)
		)
		(property "Dielectric" "X5R"
			(at 276.86 48.26 0)
			(effects
				(font
					(size 1.27 1.27)
				)
				(justify left bottom)
				(hide yes)
			)
		)
		(pin "1"
		)
		(pin "2"
		)
		(instances
			(project "OCuLink to 10GbE adapter"
				(path ""
					(reference "C10")
					(unit 1)
				)
			)
		)
	)
	(symbol
		(lib_id "antmicroResistors0402:R_30k_0402")
		(at 332.74 194.31 90)
		(unit 1)
		(exclude_from_sim no)
		(in_bom yes)
		(on_board yes)
		(dnp no)
		(property "Reference" "R32"
			(at 334.01 190.5 90)
			(effects
				(font
					(size 1.27 1.27)
					(thickness 0.15)
				)
				(justify right)
			)
		)
		(property "Value" "R_30k_0402"
			(at 345.44 173.99 0)
			(effects
				(font
					(size 1.27 1.27)
					(thickness 0.15)
				)
				(justify left bottom)
				(hide yes)
			)
		)
		(property "Footprint" "antmicro-footprints:R_0402_1005Metric"
			(at 347.98 173.99 0)
			(effects
				(font
					(size 1.27 1.27)
					(thickness 0.15)
				)
				(justify left bottom)
				(hide yes)
			)
		)
		(property "Datasheet" "https://www.bourns.com/docs/product-datasheets/cr.pdf"
			(at 350.52 173.99 0)
			(effects
				(font
					(size 1.27 1.27)
					(thickness 0.15)
				)
				(justify left bottom)
				(hide yes)
			)
		)
		(property "Description" "SMD Chip Resistor, 30 kohm, ± 1%, 63 mW, 0402 [1005 Metric], Thick Film, General Purpose"
			(at 363.22 173.99 0)
			(effects
				(font
					(size 1.27 1.27)
				)
				(justify left bottom)
				(hide yes)
			)
		)
		(property "MPN" "CR0402-FX-3002GLF"
			(at 353.06 173.99 0)
			(effects
				(font
					(size 1.27 1.27)
					(thickness 0.15)
				)
				(justify left bottom)
				(hide yes)
			)
		)
		(property "Manufacturer" "Bourns"
			(at 355.6 173.99 0)
			(effects
				(font
					(size 1.27 1.27)
					(thickness 0.15)
				)
				(justify left bottom)
				(hide yes)
			)
		)
		(property "License" "Apache-2.0"
			(at 358.14 173.99 0)
			(effects
				(font
					(size 1.27 1.27)
					(thickness 0.15)
				)
				(justify left bottom)
				(hide yes)
			)
		)
		(property "Author" "Antmicro"
			(at 360.68 173.99 0)
			(effects
				(font
					(size 1.27 1.27)
					(thickness 0.15)
				)
				(justify left bottom)
				(hide yes)
			)
		)
		(property "Val" "30k"
			(at 334.01 193.04 90)
			(effects
				(font
					(size 1.27 1.27)
					(thickness 0.15)
				)
				(justify right)
			)
		)
		(property "Tolerance" "1%"
			(at 342.9 173.99 0)
			(effects
				(font
					(size 1.27 1.27)
				)
				(justify left bottom)
				(hide yes)
			)
		)
		(pin "2"
		)
		(pin "1"
		)
		(instances
			(project "OCuLink to 10GbE adapter"
				(path ""
					(reference "R32")
					(unit 1)
				)
			)
		)
	)
	(symbol
		(lib_id "antmicroCapacitors0402:C_100n_0402")
		(at 374.65 76.2 90)
		(unit 1)
		(exclude_from_sim no)
		(in_bom yes)
		(on_board yes)
		(dnp no)
		(property "Reference" "C18"
			(at 376.428 72.39 90)
			(effects
				(font
					(size 1.27 1.27)
					(thickness 0.15)
				)
				(justify right)
			)
		)
		(property "Value" "C_100n_0402"
			(at 384.81 55.88 0)
			(effects
				(font
					(size 1.27 1.27)
					(thickness 0.15)
				)
				(justify left bottom)
				(hide yes)
			)
		)
		(property "Footprint" "antmicro-footprints:C_0402_1005Metric"
			(at 387.35 55.88 0)
			(effects
				(font
					(size 1.27 1.27)
					(thickness 0.15)
				)
				(justify left bottom)
				(hide yes)
			)
		)
		(property "Datasheet" "https://www.murata.com/products/productdetail?partno=GRM155R61H104KE14%23"
			(at 389.89 55.88 0)
			(effects
				(font
					(size 1.27 1.27)
					(thickness 0.15)
				)
				(justify left bottom)
				(hide yes)
			)
		)
		(property "Description" "SMD Multilayer Ceramic Capacitor, 0.1 µF, 50 V, 0402 [1005 Metric], ± 10%, X5R, GRM Series"
			(at 407.67 55.88 0)
			(effects
				(font
					(size 1.27 1.27)
				)
				(justify left bottom)
				(hide yes)
			)
		)
		(property "MPN" "GRM155R61H104KE14D"
			(at 392.43 55.88 0)
			(effects
				(font
					(size 1.27 1.27)
					(thickness 0.15)
				)
				(justify left bottom)
				(hide yes)
			)
		)
		(property "Manufacturer" "Murata"
			(at 394.97 55.88 0)
			(effects
				(font
					(size 1.27 1.27)
					(thickness 0.15)
				)
				(justify left bottom)
				(hide yes)
			)
		)
		(property "License" "Apache-2.0"
			(at 397.51 55.88 0)
			(effects
				(font
					(size 1.27 1.27)
					(thickness 0.15)
				)
				(justify left bottom)
				(hide yes)
			)
		)
		(property "Author" "Antmicro"
			(at 400.05 55.88 0)
			(effects
				(font
					(size 1.27 1.27)
					(thickness 0.15)
				)
				(justify left bottom)
				(hide yes)
			)
		)
		(property "Val" "100n"
			(at 376.428 74.93 90)
			(effects
				(font
					(size 1.27 1.27)
					(thickness 0.15)
				)
				(justify right)
			)
		)
		(property "Voltage" "50V"
			(at 402.59 55.88 0)
			(effects
				(font
					(size 1.27 1.27)
				)
				(justify left bottom)
				(hide yes)
			)
		)
		(property "Dielectric" "X5R"
			(at 405.13 55.88 0)
			(effects
				(font
					(size 1.27 1.27)
				)
				(justify left bottom)
				(hide yes)
			)
		)
		(pin "1"
		)
		(pin "2"
		)
		(instances
			(project "OCuLink to 10GbE adapter"
				(path ""
					(reference "C18")
					(unit 1)
				)
			)
		)
	)
	(symbol
		(lib_id "antmicroResistors0402:R_100k_0402")
		(at 256.54 114.3 270)
		(mirror x)
		(unit 1)
		(exclude_from_sim no)
		(in_bom yes)
		(on_board yes)
		(dnp no)
		(property "Reference" "R17"
			(at 255.27 110.49 90)
			(effects
				(font
					(size 1.27 1.27)
					(thickness 0.15)
				)
				(justify right)
			)
		)
		(property "Value" "R_100k_0402"
			(at 243.84 93.98 0)
			(effects
				(font
					(size 1.27 1.27)
					(thickness 0.15)
				)
				(justify left bottom)
				(hide yes)
			)
		)
		(property "Footprint" "antmicro-footprints:R_0402_1005Metric"
			(at 241.3 93.98 0)
			(effects
				(font
					(size 1.27 1.27)
					(thickness 0.15)
				)
				(justify left bottom)
				(hide yes)
			)
		)
		(property "Datasheet" "https://www.bourns.com/docs/product-datasheets/cr.pdf"
			(at 238.76 93.98 0)
			(effects
				(font
					(size 1.27 1.27)
					(thickness 0.15)
				)
				(justify left bottom)
				(hide yes)
			)
		)
		(property "Description" "SMD Chip Resistor, 100 kohm, ± 1%, 62.5 mW, 0402 [1005 Metric], Thick Film, General Purpose"
			(at 226.06 93.98 0)
			(effects
				(font
					(size 1.27 1.27)
				)
				(justify left bottom)
				(hide yes)
			)
		)
		(property "MPN" "CR0402-FX-1003GLF"
			(at 236.22 93.98 0)
			(effects
				(font
					(size 1.27 1.27)
					(thickness 0.15)
				)
				(justify left bottom)
				(hide yes)
			)
		)
		(property "Manufacturer" "Bourns"
			(at 233.68 93.98 0)
			(effects
				(font
					(size 1.27 1.27)
					(thickness 0.15)
				)
				(justify left bottom)
				(hide yes)
			)
		)
		(property "License" "Apache-2.0"
			(at 231.14 93.98 0)
			(effects
				(font
					(size 1.27 1.27)
					(thickness 0.15)
				)
				(justify left bottom)
				(hide yes)
			)
		)
		(property "Author" "Antmicro"
			(at 228.6 93.98 0)
			(effects
				(font
					(size 1.27 1.27)
					(thickness 0.15)
				)
				(justify left bottom)
				(hide yes)
			)
		)
		(property "Val" "100k"
			(at 255.27 113.03 90)
			(effects
				(font
					(size 1.27 1.27)
					(thickness 0.15)
				)
				(justify right)
			)
		)
		(property "Tolerance" "1%"
			(at 246.38 93.98 0)
			(effects
				(font
					(size 1.27 1.27)
				)
				(justify left bottom)
				(hide yes)
			)
		)
		(pin "1"
		)
		(pin "2"
		)
		(instances
			(project "OCuLink to 10GbE adapter"
				(path ""
					(reference "R17")
					(unit 1)
				)
			)
		)
	)
	(symbol
		(lib_id "antmicropower:+1V8")
		(at 387.35 233.68 90)
		(unit 1)
		(exclude_from_sim no)
		(in_bom yes)
		(on_board yes)
		(dnp no)
		(fields_autoplaced yes)
		(property "Reference" "#PWR0307"
			(at 389.89 218.44 0)
			(effects
				(font
					(size 1.27 1.27)
					(thickness 0.15)
				)
				(justify left bottom)
				(hide yes)
			)
		)
		(property "Value" "+1V88"
			(at 383.54 233.68 90)
			(effects
				(font
					(size 1.27 1.27)
					(thickness 0.15)
				)
				(justify left)
			)
		)
		(property "Footprint" ""
			(at 394.97 218.44 0)
			(effects
				(font
					(size 1.27 1.27)
					(thickness 0.15)
				)
				(justify left bottom)
				(hide yes)
			)
		)
		(property "Datasheet" ""
			(at 397.51 218.44 0)
			(effects
				(font
					(size 1.27 1.27)
					(thickness 0.15)
				)
				(justify left bottom)
				(hide yes)
			)
		)
		(property "Description" ""
			(at 387.35 233.68 0)
			(effects
				(font
					(size 1.27 1.27)
				)
				(hide yes)
			)
		)
		(property "Author" "Antmicro"
			(at 392.43 218.44 0)
			(effects
				(font
					(size 1.27 1.27)
					(thickness 0.15)
				)
				(justify left bottom)
				(hide yes)
			)
		)
		(property "License" "Apache-2.0"
			(at 394.97 218.44 0)
			(effects
				(font
					(size 1.27 1.27)
					(thickness 0.15)
				)
				(justify left bottom)
				(hide yes)
			)
		)
		(pin "1"
		)
		(instances
			(project "oculink-to-10gbe-adapter"
				(path ""
					(reference "#PWR0307")
					(unit 1)
				)
			)
		)
	)
	(symbol
		(lib_id "antmicropower:GND")
		(at 228.6 246.38 0)
		(mirror y)
		(unit 1)
		(exclude_from_sim no)
		(in_bom yes)
		(on_board yes)
		(dnp no)
		(property "Reference" "#PWR0319"
			(at 219.71 248.92 0)
			(effects
				(font
					(size 1.27 1.27)
					(thickness 0.15)
				)
				(justify left bottom)
				(hide yes)
			)
		)
		(property "Value" "GND"
			(at 228.6 250.19 0)
			(effects
				(font
					(size 1.27 1.27)
					(thickness 0.15)
				)
			)
		)
		(property "Footprint" ""
			(at 219.71 254 0)
			(effects
				(font
					(size 1.27 1.27)
					(thickness 0.15)
				)
				(justify left bottom)
				(hide yes)
			)
		)
		(property "Datasheet" ""
			(at 219.71 259.08 0)
			(effects
				(font
					(size 1.27 1.27)
					(thickness 0.15)
				)
				(justify left bottom)
				(hide yes)
			)
		)
		(property "Description" ""
			(at 228.6 246.38 0)
			(effects
				(font
					(size 1.27 1.27)
				)
				(hide yes)
			)
		)
		(property "Author" "Antmicro"
			(at 219.71 254 0)
			(effects
				(font
					(size 1.27 1.27)
					(thickness 0.15)
				)
				(justify left bottom)
				(hide yes)
			)
		)
		(property "License" "Apache-2.0"
			(at 219.71 256.54 0)
			(effects
				(font
					(size 1.27 1.27)
					(thickness 0.15)
				)
				(justify left bottom)
				(hide yes)
			)
		)
		(pin "1"
		)
		(instances
			(project "oculink-to-10gbe-adapter"
				(path ""
					(reference "#PWR0319")
					(unit 1)
				)
			)
		)
	)
	(symbol
		(lib_id "antmicroResistors0402:R_5k1_0402")
		(at 81.28 149.86 90)
		(unit 1)
		(exclude_from_sim no)
		(in_bom yes)
		(on_board yes)
		(dnp no)
		(property "Reference" "R23"
			(at 82.55 146.05 90)
			(effects
				(font
					(size 1.27 1.27)
					(thickness 0.15)
				)
				(justify right)
			)
		)
		(property "Value" "R_5k1_0402"
			(at 93.98 129.54 0)
			(effects
				(font
					(size 1.27 1.27)
					(thickness 0.15)
				)
				(justify left bottom)
				(hide yes)
			)
		)
		(property "Footprint" "antmicro-footprints:R_0402_1005Metric"
			(at 96.52 129.54 0)
			(effects
				(font
					(size 1.27 1.27)
					(thickness 0.15)
				)
				(justify left bottom)
				(hide yes)
			)
		)
		(property "Datasheet" "https://www.bourns.com/docs/product-datasheets/cr.pdf"
			(at 99.06 129.54 0)
			(effects
				(font
					(size 1.27 1.27)
					(thickness 0.15)
				)
				(justify left bottom)
				(hide yes)
			)
		)
		(property "Description" "SMD Chip Resistor, 5.1 kohm, ± 1%, 63 mW, 0402 [1005 Metric], Thick Film, General Purpose"
			(at 81.28 149.86 0)
			(effects
				(font
					(size 1.27 1.27)
				)
				(hide yes)
			)
		)
		(property "MPN" "CR0402-FX-5101GLF"
			(at 101.6 129.54 0)
			(effects
				(font
					(size 1.27 1.27)
					(thickness 0.15)
				)
				(justify left bottom)
				(hide yes)
			)
		)
		(property "Manufacturer" "Bourns"
			(at 104.14 129.54 0)
			(effects
				(font
					(size 1.27 1.27)
					(thickness 0.15)
				)
				(justify left bottom)
				(hide yes)
			)
		)
		(property "License" "Apache-2.0"
			(at 106.68 129.54 0)
			(effects
				(font
					(size 1.27 1.27)
					(thickness 0.15)
				)
				(justify left bottom)
				(hide yes)
			)
		)
		(property "Author" "Antmicro"
			(at 109.22 129.54 0)
			(effects
				(font
					(size 1.27 1.27)
					(thickness 0.15)
				)
				(justify left bottom)
				(hide yes)
			)
		)
		(property "Val" "5k1"
			(at 82.55 148.59 90)
			(effects
				(font
					(size 1.27 1.27)
					(thickness 0.15)
				)
				(justify right)
			)
		)
		(property "Tolerance" "1%"
			(at 91.44 129.54 0)
			(effects
				(font
					(size 1.27 1.27)
				)
				(justify left bottom)
				(hide yes)
			)
		)
		(pin "2"
		)
		(pin "1"
		)
		(instances
			(project "OCuLink to 10GbE adapter"
				(path ""
					(reference "R23")
					(unit 1)
				)
			)
		)
	)
	(symbol
		(lib_id "antmicroCapacitors0603:C_22u_16V_0603")
		(at 217.17 38.1 270)
		(mirror x)
		(unit 1)
		(exclude_from_sim no)
		(in_bom yes)
		(on_board yes)
		(dnp no)
		(property "Reference" "C3"
			(at 215.138 34.29 90)
			(effects
				(font
					(size 1.27 1.27)
					(thickness 0.15)
				)
				(justify right)
			)
		)
		(property "Value" "C_22u_16V_0603"
			(at 207.01 17.78 0)
			(effects
				(font
					(size 1.27 1.27)
					(thickness 0.15)
				)
				(justify left bottom)
				(hide yes)
			)
		)
		(property "Footprint" "antmicro-footprints:C_0603_1608Metric_EIA"
			(at 204.47 17.78 0)
			(effects
				(font
					(size 1.27 1.27)
					(thickness 0.15)
				)
				(justify left bottom)
				(hide yes)
			)
		)
		(property "Datasheet" "https://product.samsungsem.com/mlcc/CL10A226MO7JZN.do"
			(at 201.93 17.78 0)
			(effects
				(font
					(size 1.27 1.27)
					(thickness 0.15)
				)
				(justify left bottom)
				(hide yes)
			)
		)
		(property "Description" "SMD Multilayer Ceramic Capacitor"
			(at 217.17 38.1 0)
			(effects
				(font
					(size 1.27 1.27)
				)
				(hide yes)
			)
		)
		(property "MPN" "CL10A226MO7JZNC"
			(at 199.39 17.78 0)
			(effects
				(font
					(size 1.27 1.27)
					(thickness 0.15)
				)
				(justify left bottom)
				(hide yes)
			)
		)
		(property "Manufacturer" "Samsung Electro-Mechanics"
			(at 196.85 17.78 0)
			(effects
				(font
					(size 1.27 1.27)
					(thickness 0.15)
				)
				(justify left bottom)
				(hide yes)
			)
		)
		(property "License" "Apache-2.0"
			(at 194.31 17.78 0)
			(effects
				(font
					(size 1.27 1.27)
					(thickness 0.15)
				)
				(justify left bottom)
				(hide yes)
			)
		)
		(property "Author" "Antmicro"
			(at 191.77 17.78 0)
			(effects
				(font
					(size 1.27 1.27)
					(thickness 0.15)
				)
				(justify left bottom)
				(hide yes)
			)
		)
		(property "Val" "22u"
			(at 215.138 36.83 90)
			(effects
				(font
					(size 1.27 1.27)
					(thickness 0.15)
				)
				(justify right)
			)
		)
		(property "Voltage" "16V"
			(at 214.63 38.0935 90)
			(effects
				(font
					(size 1.27 1.27)
				)
				(justify right)
				(hide yes)
			)
		)
		(property "Dielectric" ""
			(at 186.69 17.78 0)
			(effects
				(font
					(size 1.27 1.27)
				)
				(justify left bottom)
				(hide yes)
			)
		)
		(property "Public" "False"
			(at 184.15 17.78 0)
			(effects
				(font
					(size 1.27 1.27)
				)
				(justify left bottom)
				(hide yes)
			)
		)
		(pin "2"
		)
		(pin "1"
		)
		(instances
			(project "OCuLink to 10GbE adapter"
				(path ""
					(reference "C3")
					(unit 1)
				)
			)
		)
	)
	(symbol
		(lib_id "antmicropower:GND")
		(at 247.65 157.48 0)
		(unit 1)
		(exclude_from_sim no)
		(in_bom yes)
		(on_board yes)
		(dnp no)
		(property "Reference" "#PWR040"
			(at 256.54 160.02 0)
			(effects
				(font
					(size 1.27 1.27)
					(thickness 0.15)
				)
				(justify left bottom)
				(hide yes)
			)
		)
		(property "Value" "GND"
			(at 247.65 161.29 0)
			(effects
				(font
					(size 1.27 1.27)
					(thickness 0.15)
				)
			)
		)
		(property "Footprint" ""
			(at 256.54 165.1 0)
			(effects
				(font
					(size 1.27 1.27)
					(thickness 0.15)
				)
				(justify left bottom)
				(hide yes)
			)
		)
		(property "Datasheet" ""
			(at 256.54 170.18 0)
			(effects
				(font
					(size 1.27 1.27)
					(thickness 0.15)
				)
				(justify left bottom)
				(hide yes)
			)
		)
		(property "Description" ""
			(at 247.65 157.48 0)
			(effects
				(font
					(size 1.27 1.27)
				)
				(hide yes)
			)
		)
		(property "Author" "Antmicro"
			(at 256.54 165.1 0)
			(effects
				(font
					(size 1.27 1.27)
					(thickness 0.15)
				)
				(justify left bottom)
				(hide yes)
			)
		)
		(property "License" "Apache-2.0"
			(at 256.54 167.64 0)
			(effects
				(font
					(size 1.27 1.27)
					(thickness 0.15)
				)
				(justify left bottom)
				(hide yes)
			)
		)
		(pin "1"
		)
		(instances
			(project "OCuLink to 10GbE adapter"
				(path ""
					(reference "#PWR040")
					(unit 1)
				)
			)
		)
	)
	(symbol
		(lib_id "antmicroCapacitors0402:C_33p_0402")
		(at 327.66 33.02 270)
		(mirror x)
		(unit 1)
		(exclude_from_sim no)
		(in_bom yes)
		(on_board yes)
		(dnp no)
		(property "Reference" "C2"
			(at 325.882 29.21 90)
			(effects
				(font
					(size 1.27 1.27)
					(thickness 0.15)
				)
				(justify right)
			)
		)
		(property "Value" "C_33p_0402"
			(at 317.5 12.7 0)
			(effects
				(font
					(size 1.27 1.27)
					(thickness 0.15)
				)
				(justify left bottom)
				(hide yes)
			)
		)
		(property "Footprint" "antmicro-footprints:C_0402_1005Metric"
			(at 314.96 12.7 0)
			(effects
				(font
					(size 1.27 1.27)
					(thickness 0.15)
				)
				(justify left bottom)
				(hide yes)
			)
		)
		(property "Datasheet" "https://spicat.kyocera-avx.com/product/mlcc/chartview/04025A330FAT2A/"
			(at 312.42 12.7 0)
			(effects
				(font
					(size 1.27 1.27)
					(thickness 0.15)
				)
				(justify left bottom)
				(hide yes)
			)
		)
		(property "Description" "SMD Multilayer Ceramic Capacitor, 33 pF, 50 V, 0402 [1005 Metric], ± 5%, C0G / NP0, MC"
			(at 294.64 12.7 0)
			(effects
				(font
					(size 1.27 1.27)
				)
				(justify left bottom)
				(hide yes)
			)
		)
		(property "MPN" "04025A330FAT2A"
			(at 309.88 12.7 0)
			(effects
				(font
					(size 1.27 1.27)
					(thickness 0.15)
				)
				(justify left bottom)
				(hide yes)
			)
		)
		(property "Manufacturer" "KYOCERA AVX"
			(at 307.34 12.7 0)
			(effects
				(font
					(size 1.27 1.27)
					(thickness 0.15)
				)
				(justify left bottom)
				(hide yes)
			)
		)
		(property "License" "Apache-2.0"
			(at 304.8 12.7 0)
			(effects
				(font
					(size 1.27 1.27)
					(thickness 0.15)
				)
				(justify left bottom)
				(hide yes)
			)
		)
		(property "Author" "Antmicro"
			(at 302.26 12.7 0)
			(effects
				(font
					(size 1.27 1.27)
					(thickness 0.15)
				)
				(justify left bottom)
				(hide yes)
			)
		)
		(property "Val" "33p"
			(at 325.882 31.75 90)
			(effects
				(font
					(size 1.27 1.27)
					(thickness 0.15)
				)
				(justify right)
			)
		)
		(property "Voltage" ""
			(at 299.72 12.7 0)
			(effects
				(font
					(size 1.27 1.27)
				)
				(justify left bottom)
				(hide yes)
			)
		)
		(property "Dielectric" ""
			(at 297.18 12.7 0)
			(effects
				(font
					(size 1.27 1.27)
				)
				(justify left bottom)
				(hide yes)
			)
		)
		(pin "2"
		)
		(pin "1"
		)
		(instances
			(project "OCuLink to 10GbE adapter"
				(path ""
					(reference "C2")
					(unit 1)
				)
			)
		)
	)
	(symbol
		(lib_id "antmicroCapacitors0603:C_22u_16V_0603")
		(at 344.17 190.5 90)
		(unit 1)
		(exclude_from_sim no)
		(in_bom yes)
		(on_board yes)
		(dnp no)
		(property "Reference" "C44"
			(at 346.202 186.69 90)
			(effects
				(font
					(size 1.27 1.27)
					(thickness 0.15)
				)
				(justify right)
			)
		)
		(property "Value" "C_22u_16V_0603"
			(at 354.33 170.18 0)
			(effects
				(font
					(size 1.27 1.27)
					(thickness 0.15)
				)
				(justify left bottom)
				(hide yes)
			)
		)
		(property "Footprint" "antmicro-footprints:C_0603_1608Metric_EIA"
			(at 356.87 170.18 0)
			(effects
				(font
					(size 1.27 1.27)
					(thickness 0.15)
				)
				(justify left bottom)
				(hide yes)
			)
		)
		(property "Datasheet" "https://product.samsungsem.com/mlcc/CL10A226MO7JZN.do"
			(at 359.41 170.18 0)
			(effects
				(font
					(size 1.27 1.27)
					(thickness 0.15)
				)
				(justify left bottom)
				(hide yes)
			)
		)
		(property "Description" "SMD Multilayer Ceramic Capacitor"
			(at 344.17 190.5 0)
			(effects
				(font
					(size 1.27 1.27)
				)
				(hide yes)
			)
		)
		(property "MPN" "CL10A226MO7JZNC"
			(at 361.95 170.18 0)
			(effects
				(font
					(size 1.27 1.27)
					(thickness 0.15)
				)
				(justify left bottom)
				(hide yes)
			)
		)
		(property "Manufacturer" "Samsung Electro-Mechanics"
			(at 364.49 170.18 0)
			(effects
				(font
					(size 1.27 1.27)
					(thickness 0.15)
				)
				(justify left bottom)
				(hide yes)
			)
		)
		(property "License" "Apache-2.0"
			(at 367.03 170.18 0)
			(effects
				(font
					(size 1.27 1.27)
					(thickness 0.15)
				)
				(justify left bottom)
				(hide yes)
			)
		)
		(property "Author" "Antmicro"
			(at 369.57 170.18 0)
			(effects
				(font
					(size 1.27 1.27)
					(thickness 0.15)
				)
				(justify left bottom)
				(hide yes)
			)
		)
		(property "Val" "22u"
			(at 346.202 189.23 90)
			(effects
				(font
					(size 1.27 1.27)
					(thickness 0.15)
				)
				(justify right)
			)
		)
		(property "Voltage" "16V"
			(at 346.71 190.4935 90)
			(effects
				(font
					(size 1.27 1.27)
				)
				(justify right)
				(hide yes)
			)
		)
		(property "Dielectric" ""
			(at 374.65 170.18 0)
			(effects
				(font
					(size 1.27 1.27)
				)
				(justify left bottom)
				(hide yes)
			)
		)
		(property "Public" "False"
			(at 377.19 170.18 0)
			(effects
				(font
					(size 1.27 1.27)
				)
				(justify left bottom)
				(hide yes)
			)
		)
		(pin "2"
		)
		(pin "1"
		)
		(instances
			(project "OCuLink to 10GbE adapter"
				(path ""
					(reference "C44")
					(unit 1)
				)
			)
		)
	)
	(symbol
		(lib_id "antmicropower:GND")
		(at 196.85 43.18 0)
		(unit 1)
		(exclude_from_sim no)
		(in_bom yes)
		(on_board yes)
		(dnp no)
		(property "Reference" "#PWR03"
			(at 205.74 45.72 0)
			(effects
				(font
					(size 1.27 1.27)
					(thickness 0.15)
				)
				(justify left bottom)
				(hide yes)
			)
		)
		(property "Value" "GND"
			(at 196.85 46.99 0)
			(effects
				(font
					(size 1.27 1.27)
					(thickness 0.15)
				)
			)
		)
		(property "Footprint" ""
			(at 205.74 50.8 0)
			(effects
				(font
					(size 1.27 1.27)
					(thickness 0.15)
				)
				(justify left bottom)
				(hide yes)
			)
		)
		(property "Datasheet" ""
			(at 205.74 55.88 0)
			(effects
				(font
					(size 1.27 1.27)
					(thickness 0.15)
				)
				(justify left bottom)
				(hide yes)
			)
		)
		(property "Description" ""
			(at 196.85 43.18 0)
			(effects
				(font
					(size 1.27 1.27)
				)
				(hide yes)
			)
		)
		(property "Author" "Antmicro"
			(at 205.74 50.8 0)
			(effects
				(font
					(size 1.27 1.27)
					(thickness 0.15)
				)
				(justify left bottom)
				(hide yes)
			)
		)
		(property "License" "Apache-2.0"
			(at 205.74 53.34 0)
			(effects
				(font
					(size 1.27 1.27)
					(thickness 0.15)
				)
				(justify left bottom)
				(hide yes)
			)
		)
		(pin "1"
		)
		(instances
			(project "OCuLink to 10GbE adapter"
				(path ""
					(reference "#PWR03")
					(unit 1)
				)
			)
		)
	)
	(symbol
		(lib_id "antmicroCapacitors0603:C_22u_16V_0603")
		(at 344.17 38.1 90)
		(unit 1)
		(exclude_from_sim no)
		(in_bom yes)
		(on_board yes)
		(dnp no)
		(property "Reference" "C7"
			(at 346.202 34.29 90)
			(effects
				(font
					(size 1.27 1.27)
					(thickness 0.15)
				)
				(justify right)
			)
		)
		(property "Value" "C_22u_16V_0603"
			(at 354.33 17.78 0)
			(effects
				(font
					(size 1.27 1.27)
					(thickness 0.15)
				)
				(justify left bottom)
				(hide yes)
			)
		)
		(property "Footprint" "antmicro-footprints:C_0603_1608Metric_EIA"
			(at 356.87 17.78 0)
			(effects
				(font
					(size 1.27 1.27)
					(thickness 0.15)
				)
				(justify left bottom)
				(hide yes)
			)
		)
		(property "Datasheet" "https://product.samsungsem.com/mlcc/CL10A226MO7JZN.do"
			(at 359.41 17.78 0)
			(effects
				(font
					(size 1.27 1.27)
					(thickness 0.15)
				)
				(justify left bottom)
				(hide yes)
			)
		)
		(property "Description" "SMD Multilayer Ceramic Capacitor"
			(at 344.17 38.1 0)
			(effects
				(font
					(size 1.27 1.27)
				)
				(hide yes)
			)
		)
		(property "MPN" "CL10A226MO7JZNC"
			(at 361.95 17.78 0)
			(effects
				(font
					(size 1.27 1.27)
					(thickness 0.15)
				)
				(justify left bottom)
				(hide yes)
			)
		)
		(property "Manufacturer" "Samsung Electro-Mechanics"
			(at 364.49 17.78 0)
			(effects
				(font
					(size 1.27 1.27)
					(thickness 0.15)
				)
				(justify left bottom)
				(hide yes)
			)
		)
		(property "License" "Apache-2.0"
			(at 367.03 17.78 0)
			(effects
				(font
					(size 1.27 1.27)
					(thickness 0.15)
				)
				(justify left bottom)
				(hide yes)
			)
		)
		(property "Author" "Antmicro"
			(at 369.57 17.78 0)
			(effects
				(font
					(size 1.27 1.27)
					(thickness 0.15)
				)
				(justify left bottom)
				(hide yes)
			)
		)
		(property "Val" "22u"
			(at 346.202 36.83 90)
			(effects
				(font
					(size 1.27 1.27)
					(thickness 0.15)
				)
				(justify right)
			)
		)
		(property "Voltage" "16V"
			(at 346.71 38.0935 90)
			(effects
				(font
					(size 1.27 1.27)
				)
				(justify right)
				(hide yes)
			)
		)
		(property "Dielectric" ""
			(at 374.65 17.78 0)
			(effects
				(font
					(size 1.27 1.27)
				)
				(justify left bottom)
				(hide yes)
			)
		)
		(property "Public" "False"
			(at 377.19 17.78 0)
			(effects
				(font
					(size 1.27 1.27)
				)
				(justify left bottom)
				(hide yes)
			)
		)
		(pin "2"
		)
		(pin "1"
		)
		(instances
			(project "OCuLink to 10GbE adapter"
				(path ""
					(reference "C7")
					(unit 1)
				)
			)
		)
	)
	(symbol
		(lib_id "antmicropower:GND")
		(at 364.49 43.18 0)
		(unit 1)
		(exclude_from_sim no)
		(in_bom yes)
		(on_board yes)
		(dnp no)
		(property "Reference" "#PWR0334"
			(at 373.38 45.72 0)
			(effects
				(font
					(size 1.27 1.27)
					(thickness 0.15)
				)
				(justify left bottom)
				(hide yes)
			)
		)
		(property "Value" "GND"
			(at 364.49 46.99 0)
			(effects
				(font
					(size 1.27 1.27)
					(thickness 0.15)
				)
			)
		)
		(property "Footprint" ""
			(at 373.38 50.8 0)
			(effects
				(font
					(size 1.27 1.27)
					(thickness 0.15)
				)
				(justify left bottom)
				(hide yes)
			)
		)
		(property "Datasheet" ""
			(at 373.38 55.88 0)
			(effects
				(font
					(size 1.27 1.27)
					(thickness 0.15)
				)
				(justify left bottom)
				(hide yes)
			)
		)
		(property "Description" ""
			(at 364.49 43.18 0)
			(effects
				(font
					(size 1.27 1.27)
				)
				(hide yes)
			)
		)
		(property "Author" "Antmicro"
			(at 373.38 50.8 0)
			(effects
				(font
					(size 1.27 1.27)
					(thickness 0.15)
				)
				(justify left bottom)
				(hide yes)
			)
		)
		(property "License" "Apache-2.0"
			(at 373.38 53.34 0)
			(effects
				(font
					(size 1.27 1.27)
					(thickness 0.15)
				)
				(justify left bottom)
				(hide yes)
			)
		)
		(pin "1"
		)
		(instances
			(project "OCuLink to 10GbE adapter"
				(path ""
					(reference "#PWR0334")
					(unit 1)
				)
			)
		)
	)
	(symbol
		(lib_id "antmicropower:PWR_FLAG")
		(at 391.16 60.96 0)
		(unit 1)
		(exclude_from_sim no)
		(in_bom yes)
		(on_board yes)
		(dnp no)
		(property "Reference" "#FLG02"
			(at 391.16 59.055 0)
			(effects
				(font
					(size 1.27 1.27)
				)
				(hide yes)
			)
		)
		(property "Value" "PWR_FLAG"
			(at 391.16 57.15 0)
			(effects
				(font
					(size 1.27 1.27)
				)
			)
		)
		(property "Footprint" ""
			(at 391.16 60.96 0)
			(effects
				(font
					(size 1.27 1.27)
				)
				(hide yes)
			)
		)
		(property "Datasheet" ""
			(at 391.16 60.96 0)
			(effects
				(font
					(size 1.27 1.27)
				)
				(hide yes)
			)
		)
		(property "Description" ""
			(at 391.16 60.96 0)
			(effects
				(font
					(size 1.27 1.27)
				)
				(hide yes)
			)
		)
		(pin "1"
		)
		(instances
			(project "OCuLink to 10GbE adapter"
				(path ""
					(reference "#FLG02")
					(unit 1)
				)
			)
		)
	)
	(symbol
		(lib_id "antmicroResistors0402:R_1k_0402")
		(at 177.8 231.14 90)
		(unit 1)
		(exclude_from_sim no)
		(in_bom yes)
		(on_board yes)
		(dnp no)
		(property "Reference" "R144"
			(at 179.07 227.33 90)
			(effects
				(font
					(size 1.27 1.27)
					(thickness 0.15)
				)
				(justify right)
			)
		)
		(property "Value" "R_1k_0402"
			(at 190.5 210.82 0)
			(effects
				(font
					(size 1.27 1.27)
					(thickness 0.15)
				)
				(justify left bottom)
				(hide yes)
			)
		)
		(property "Footprint" "antmicro-footprints:R_0402_1005Metric"
			(at 193.04 210.82 0)
			(effects
				(font
					(size 1.27 1.27)
					(thickness 0.15)
				)
				(justify left bottom)
				(hide yes)
			)
		)
		(property "Datasheet" "https://www.bourns.com/docs/product-datasheets/cr.pdf"
			(at 195.58 210.82 0)
			(effects
				(font
					(size 1.27 1.27)
					(thickness 0.15)
				)
				(justify left bottom)
				(hide yes)
			)
		)
		(property "Description" "SMD Chip Resistor, 1 kohm, ± 1%, 63 mW, 0402 [1005 Metric], Thick Film, General Purpose"
			(at 208.28 210.82 0)
			(effects
				(font
					(size 1.27 1.27)
				)
				(justify left bottom)
				(hide yes)
			)
		)
		(property "MPN" "CR0402-FX-1001GLF"
			(at 198.12 210.82 0)
			(effects
				(font
					(size 1.27 1.27)
					(thickness 0.15)
				)
				(justify left bottom)
				(hide yes)
			)
		)
		(property "Manufacturer" "Bourns"
			(at 200.66 210.82 0)
			(effects
				(font
					(size 1.27 1.27)
					(thickness 0.15)
				)
				(justify left bottom)
				(hide yes)
			)
		)
		(property "License" "Apache-2.0"
			(at 203.2 210.82 0)
			(effects
				(font
					(size 1.27 1.27)
					(thickness 0.15)
				)
				(justify left bottom)
				(hide yes)
			)
		)
		(property "Author" "Antmicro"
			(at 205.74 210.82 0)
			(effects
				(font
					(size 1.27 1.27)
					(thickness 0.15)
				)
				(justify left bottom)
				(hide yes)
			)
		)
		(property "Val" "1k"
			(at 179.07 229.87 90)
			(effects
				(font
					(size 1.27 1.27)
					(thickness 0.15)
				)
				(justify right)
			)
		)
		(property "Tolerance" "1%"
			(at 187.96 210.82 0)
			(effects
				(font
					(size 1.27 1.27)
				)
				(justify left bottom)
				(hide yes)
			)
		)
		(pin "1"
		)
		(pin "2"
		)
		(instances
			(project "oculink-to-10gbe-adapter"
				(path ""
					(reference "R144")
					(unit 1)
				)
			)
		)
	)
	(symbol
		(lib_id "antmicroResistors0402:R_0R_0402")
		(at 261.62 111.76 0)
		(unit 1)
		(exclude_from_sim no)
		(in_bom yes)
		(on_board yes)
		(dnp no)
		(property "Reference" "R16"
			(at 264.16 109.474 0)
			(effects
				(font
					(size 1.27 1.27)
					(thickness 0.15)
				)
			)
		)
		(property "Value" "R_0R_0402"
			(at 281.94 124.46 0)
			(effects
				(font
					(size 1.27 1.27)
					(thickness 0.15)
				)
				(justify left bottom)
				(hide yes)
			)
		)
		(property "Footprint" "antmicro-footprints:R_0402_1005Metric"
			(at 281.94 127 0)
			(effects
				(font
					(size 1.27 1.27)
					(thickness 0.15)
				)
				(justify left bottom)
				(hide yes)
			)
		)
		(property "Datasheet" "https://industrial.panasonic.com/cdbs/www-data/pdf/RDA0000/AOA0000C301.pdf"
			(at 281.94 129.54 0)
			(effects
				(font
					(size 1.27 1.27)
					(thickness 0.15)
				)
				(justify left bottom)
				(hide yes)
			)
		)
		(property "Description" "SMD Chip Resistor, Jumper, 0 ohm, 100 mW, 0402 [1005 Metric], Thick Film, General Purpose"
			(at 281.94 144.78 0)
			(effects
				(font
					(size 1.27 1.27)
				)
				(justify left bottom)
				(hide yes)
			)
		)
		(property "MPN" "ERJ2GE0R00X"
			(at 281.94 132.08 0)
			(effects
				(font
					(size 1.27 1.27)
					(thickness 0.15)
				)
				(justify left bottom)
				(hide yes)
			)
		)
		(property "Manufacturer" "Panasonic"
			(at 281.94 134.62 0)
			(effects
				(font
					(size 1.27 1.27)
					(thickness 0.15)
				)
				(justify left bottom)
				(hide yes)
			)
		)
		(property "License" "Apache-2.0"
			(at 281.94 137.16 0)
			(effects
				(font
					(size 1.27 1.27)
					(thickness 0.15)
				)
				(justify left bottom)
				(hide yes)
			)
		)
		(property "Author" "Antmicro"
			(at 281.94 139.7 0)
			(effects
				(font
					(size 1.27 1.27)
					(thickness 0.15)
				)
				(justify left bottom)
				(hide yes)
			)
		)
		(property "Val" "0R"
			(at 264.16 114.046 0)
			(effects
				(font
					(size 1.27 1.27)
					(thickness 0.15)
				)
			)
		)
		(property "Tolerance" "~"
			(at 281.94 121.92 0)
			(effects
				(font
					(size 1.27 1.27)
				)
				(justify left bottom)
				(hide yes)
			)
		)
		(property "Current" "1A"
			(at 281.94 142.24 0)
			(effects
				(font
					(size 1.27 1.27)
					(thickness 0.15)
				)
				(justify left bottom)
				(hide yes)
			)
		)
		(pin "2"
		)
		(pin "1"
		)
		(instances
			(project "OCuLink to 10GbE adapter"
				(path ""
					(reference "R16")
					(unit 1)
				)
			)
		)
	)
	(symbol
		(lib_id "antmicroFixedInductors:L_1u_10A_Bourns-SRP4021HMT")
		(at 314.96 177.8 0)
		(unit 1)
		(exclude_from_sim no)
		(in_bom yes)
		(on_board yes)
		(dnp no)
		(fields_autoplaced yes)
		(property "Reference" "L5"
			(at 317.5 172.72 0)
			(effects
				(font
					(size 1.27 1.27)
					(thickness 0.15)
				)
			)
		)
		(property "Value" "L_1u_10A_Bourns-SRP4021HMT"
			(at 330.2 187.96 0)
			(effects
				(font
					(size 1.27 1.27)
					(thickness 0.15)
				)
				(justify left bottom)
				(hide yes)
			)
		)
		(property "Footprint" "antmicro-footprints:L_Bourns-SRP4021HMT"
			(at 330.2 190.5 0)
			(effects
				(font
					(size 1.27 1.27)
					(thickness 0.15)
				)
				(justify left bottom)
				(hide yes)
			)
		)
		(property "Datasheet" "https://www.mouser.com/datasheet/2/54/Bourns_04_01_2025_SRP4021HMT_Datasheet-3580094.pdf"
			(at 330.2 193.04 0)
			(effects
				(font
					(size 1.27 1.27)
					(thickness 0.15)
				)
				(justify left bottom)
				(hide yes)
			)
		)
		(property "Description" "Power Inductors - SMD Ind,4.1x4.2x1.9mm,1uH+/-20%,10A, Shielded"
			(at 330.2 195.58 0)
			(effects
				(font
					(size 1.27 1.27)
					(thickness 0.15)
				)
				(justify left bottom)
				(hide yes)
			)
		)
		(property "Val" "1u/10A"
			(at 317.5 175.26 0)
			(effects
				(font
					(size 1.27 1.27)
					(thickness 0.15)
				)
			)
		)
		(property "Manufacturer" "Bourns"
			(at 330.2 198.12 0)
			(effects
				(font
					(size 1.27 1.27)
					(thickness 0.15)
				)
				(justify left bottom)
				(hide yes)
			)
		)
		(property "MPN" "SRP4021HMT-1R0M"
			(at 330.2 200.66 0)
			(effects
				(font
					(size 1.27 1.27)
					(thickness 0.15)
				)
				(justify left bottom)
				(hide yes)
			)
		)
		(property "ISat" ""
			(at 328.93 194.31 0)
			(effects
				(font
					(size 1.27 1.27)
				)
				(justify left)
				(hide yes)
			)
		)
		(property "Isat" "8A"
			(at 330.2 203.2 0)
			(effects
				(font
					(size 1.27 1.27)
					(thickness 0.15)
				)
				(justify left bottom)
				(hide yes)
			)
		)
		(property "IMax" ""
			(at 328.93 198.12 0)
			(effects
				(font
					(size 1.27 1.27)
					(thickness 0.15)
				)
				(justify left bottom)
				(hide yes)
			)
		)
		(property "Imax" "10A"
			(at 330.2 205.74 0)
			(effects
				(font
					(size 1.27 1.27)
					(thickness 0.15)
				)
				(justify left bottom)
				(hide yes)
			)
		)
		(property "Size" "4.2x4.1"
			(at 330.2 208.28 0)
			(effects
				(font
					(size 1.27 1.27)
					(thickness 0.15)
				)
				(justify left bottom)
				(hide yes)
			)
		)
		(property "Author" "Antmicro"
			(at 330.2 210.82 0)
			(effects
				(font
					(size 1.27 1.27)
					(thickness 0.15)
				)
				(justify left bottom)
				(hide yes)
			)
		)
		(property "License" "Apache-2.0"
			(at 330.2 213.36 0)
			(effects
				(font
					(size 1.27 1.27)
					(thickness 0.15)
				)
				(justify left bottom)
				(hide yes)
			)
		)
		(pin "1"
		)
		(pin "2"
		)
		(instances
			(project "OCuLink to 10GbE adapter"
				(path ""
					(reference "L5")
					(unit 1)
				)
			)
		)
	)
	(symbol
		(lib_id "antmicroCapacitors0402:C_100n_0402")
		(at 307.34 30.48 270)
		(mirror x)
		(unit 1)
		(exclude_from_sim no)
		(in_bom yes)
		(on_board yes)
		(dnp no)
		(property "Reference" "C1"
			(at 309.118 26.924 90)
			(effects
				(font
					(size 1.27 1.27)
					(thickness 0.15)
				)
				(justify left)
			)
		)
		(property "Value" "C_100n_0402"
			(at 297.18 10.16 0)
			(effects
				(font
					(size 1.27 1.27)
					(thickness 0.15)
				)
				(justify left bottom)
				(hide yes)
			)
		)
		(property "Footprint" "antmicro-footprints:C_0402_1005Metric"
			(at 294.64 10.16 0)
			(effects
				(font
					(size 1.27 1.27)
					(thickness 0.15)
				)
				(justify left bottom)
				(hide yes)
			)
		)
		(property "Datasheet" "https://www.murata.com/products/productdetail?partno=GRM155R61H104KE14%23"
			(at 292.1 10.16 0)
			(effects
				(font
					(size 1.27 1.27)
					(thickness 0.15)
				)
				(justify left bottom)
				(hide yes)
			)
		)
		(property "Description" "SMD Multilayer Ceramic Capacitor, 0.1 µF, 50 V, 0402 [1005 Metric], ± 10%, X5R, GRM Series"
			(at 274.32 10.16 0)
			(effects
				(font
					(size 1.27 1.27)
				)
				(justify left bottom)
				(hide yes)
			)
		)
		(property "MPN" "GRM155R61H104KE14D"
			(at 289.56 10.16 0)
			(effects
				(font
					(size 1.27 1.27)
					(thickness 0.15)
				)
				(justify left bottom)
				(hide yes)
			)
		)
		(property "Manufacturer" "Murata"
			(at 287.02 10.16 0)
			(effects
				(font
					(size 1.27 1.27)
					(thickness 0.15)
				)
				(justify left bottom)
				(hide yes)
			)
		)
		(property "License" "Apache-2.0"
			(at 284.48 10.16 0)
			(effects
				(font
					(size 1.27 1.27)
					(thickness 0.15)
				)
				(justify left bottom)
				(hide yes)
			)
		)
		(property "Author" "Antmicro"
			(at 281.94 10.16 0)
			(effects
				(font
					(size 1.27 1.27)
					(thickness 0.15)
				)
				(justify left bottom)
				(hide yes)
			)
		)
		(property "Val" "100n"
			(at 309.118 29.464 90)
			(effects
				(font
					(size 1.27 1.27)
					(thickness 0.15)
				)
				(justify left)
			)
		)
		(property "Voltage" "50V"
			(at 279.4 10.16 0)
			(effects
				(font
					(size 1.27 1.27)
				)
				(justify left bottom)
				(hide yes)
			)
		)
		(property "Dielectric" "X5R"
			(at 276.86 10.16 0)
			(effects
				(font
					(size 1.27 1.27)
				)
				(justify left bottom)
				(hide yes)
			)
		)
		(pin "1"
		)
		(pin "2"
		)
		(instances
			(project "OCuLink to 10GbE adapter"
				(path ""
					(reference "C1")
					(unit 1)
				)
			)
		)
	)
	(symbol
		(lib_id "antmicroFixedInductors:L_1u_10A_Bourns-SRP4021HMT")
		(at 314.96 101.6 0)
		(unit 1)
		(exclude_from_sim no)
		(in_bom yes)
		(on_board yes)
		(dnp no)
		(fields_autoplaced yes)
		(property "Reference" "L3"
			(at 317.5 96.52 0)
			(effects
				(font
					(size 1.27 1.27)
					(thickness 0.15)
				)
			)
		)
		(property "Value" "L_1u_10A_Bourns-SRP4021HMT"
			(at 330.2 111.76 0)
			(effects
				(font
					(size 1.27 1.27)
					(thickness 0.15)
				)
				(justify left bottom)
				(hide yes)
			)
		)
		(property "Footprint" "antmicro-footprints:L_Bourns-SRP4021HMT"
			(at 330.2 114.3 0)
			(effects
				(font
					(size 1.27 1.27)
					(thickness 0.15)
				)
				(justify left bottom)
				(hide yes)
			)
		)
		(property "Datasheet" "https://www.mouser.com/datasheet/2/54/Bourns_04_01_2025_SRP4021HMT_Datasheet-3580094.pdf"
			(at 330.2 116.84 0)
			(effects
				(font
					(size 1.27 1.27)
					(thickness 0.15)
				)
				(justify left bottom)
				(hide yes)
			)
		)
		(property "Description" "Power Inductors - SMD Ind,4.1x4.2x1.9mm,1uH+/-20%,10A, Shielded"
			(at 330.2 119.38 0)
			(effects
				(font
					(size 1.27 1.27)
					(thickness 0.15)
				)
				(justify left bottom)
				(hide yes)
			)
		)
		(property "Val" "1u/10A"
			(at 317.5 99.06 0)
			(effects
				(font
					(size 1.27 1.27)
					(thickness 0.15)
				)
			)
		)
		(property "Manufacturer" "Bourns"
			(at 330.2 121.92 0)
			(effects
				(font
					(size 1.27 1.27)
					(thickness 0.15)
				)
				(justify left bottom)
				(hide yes)
			)
		)
		(property "MPN" "SRP4021HMT-1R0M"
			(at 330.2 124.46 0)
			(effects
				(font
					(size 1.27 1.27)
					(thickness 0.15)
				)
				(justify left bottom)
				(hide yes)
			)
		)
		(property "ISat" ""
			(at 328.93 118.11 0)
			(effects
				(font
					(size 1.27 1.27)
				)
				(justify left)
				(hide yes)
			)
		)
		(property "Isat" "8A"
			(at 330.2 127 0)
			(effects
				(font
					(size 1.27 1.27)
					(thickness 0.15)
				)
				(justify left bottom)
				(hide yes)
			)
		)
		(property "IMax" ""
			(at 328.93 121.92 0)
			(effects
				(font
					(size 1.27 1.27)
					(thickness 0.15)
				)
				(justify left bottom)
				(hide yes)
			)
		)
		(property "Imax" "10A"
			(at 330.2 129.54 0)
			(effects
				(font
					(size 1.27 1.27)
					(thickness 0.15)
				)
				(justify left bottom)
				(hide yes)
			)
		)
		(property "Size" "4.2x4.1"
			(at 330.2 132.08 0)
			(effects
				(font
					(size 1.27 1.27)
					(thickness 0.15)
				)
				(justify left bottom)
				(hide yes)
			)
		)
		(property "Author" "Antmicro"
			(at 330.2 134.62 0)
			(effects
				(font
					(size 1.27 1.27)
					(thickness 0.15)
				)
				(justify left bottom)
				(hide yes)
			)
		)
		(property "License" "Apache-2.0"
			(at 330.2 137.16 0)
			(effects
				(font
					(size 1.27 1.27)
					(thickness 0.15)
				)
				(justify left bottom)
				(hide yes)
			)
		)
		(pin "1"
		)
		(pin "2"
		)
		(instances
			(project "OCuLink to 10GbE adapter"
				(path ""
					(reference "L3")
					(unit 1)
				)
			)
		)
	)
	(symbol
		(lib_id "antmicroCapacitors0402:C_100n_0402")
		(at 374.65 152.4 90)
		(unit 1)
		(exclude_from_sim no)
		(in_bom yes)
		(on_board yes)
		(dnp no)
		(property "Reference" "C36"
			(at 376.428 148.59 90)
			(effects
				(font
					(size 1.27 1.27)
					(thickness 0.15)
				)
				(justify right)
			)
		)
		(property "Value" "C_100n_0402"
			(at 384.81 132.08 0)
			(effects
				(font
					(size 1.27 1.27)
					(thickness 0.15)
				)
				(justify left bottom)
				(hide yes)
			)
		)
		(property "Footprint" "antmicro-footprints:C_0402_1005Metric"
			(at 387.35 132.08 0)
			(effects
				(font
					(size 1.27 1.27)
					(thickness 0.15)
				)
				(justify left bottom)
				(hide yes)
			)
		)
		(property "Datasheet" "https://www.murata.com/products/productdetail?partno=GRM155R61H104KE14%23"
			(at 389.89 132.08 0)
			(effects
				(font
					(size 1.27 1.27)
					(thickness 0.15)
				)
				(justify left bottom)
				(hide yes)
			)
		)
		(property "Description" "SMD Multilayer Ceramic Capacitor, 0.1 µF, 50 V, 0402 [1005 Metric], ± 10%, X5R, GRM Series"
			(at 407.67 132.08 0)
			(effects
				(font
					(size 1.27 1.27)
				)
				(justify left bottom)
				(hide yes)
			)
		)
		(property "MPN" "GRM155R61H104KE14D"
			(at 392.43 132.08 0)
			(effects
				(font
					(size 1.27 1.27)
					(thickness 0.15)
				)
				(justify left bottom)
				(hide yes)
			)
		)
		(property "Manufacturer" "Murata"
			(at 394.97 132.08 0)
			(effects
				(font
					(size 1.27 1.27)
					(thickness 0.15)
				)
				(justify left bottom)
				(hide yes)
			)
		)
		(property "License" "Apache-2.0"
			(at 397.51 132.08 0)
			(effects
				(font
					(size 1.27 1.27)
					(thickness 0.15)
				)
				(justify left bottom)
				(hide yes)
			)
		)
		(property "Author" "Antmicro"
			(at 400.05 132.08 0)
			(effects
				(font
					(size 1.27 1.27)
					(thickness 0.15)
				)
				(justify left bottom)
				(hide yes)
			)
		)
		(property "Val" "100n"
			(at 376.428 151.13 90)
			(effects
				(font
					(size 1.27 1.27)
					(thickness 0.15)
				)
				(justify right)
			)
		)
		(property "Voltage" "50V"
			(at 402.59 132.08 0)
			(effects
				(font
					(size 1.27 1.27)
				)
				(justify left bottom)
				(hide yes)
			)
		)
		(property "Dielectric" "X5R"
			(at 405.13 132.08 0)
			(effects
				(font
					(size 1.27 1.27)
				)
				(justify left bottom)
				(hide yes)
			)
		)
		(pin "1"
		)
		(pin "2"
		)
		(instances
			(project "OCuLink to 10GbE adapter"
				(path ""
					(reference "C36")
					(unit 1)
				)
			)
		)
	)
	(symbol
		(lib_id "antmicroTestPoints:TP_0.75mm_SMD")
		(at 358.14 62.23 90)
		(unit 1)
		(exclude_from_sim no)
		(in_bom no)
		(on_board yes)
		(dnp no)
		(property "Reference" "TP20"
			(at 358.14 57.15 90)
			(effects
				(font
					(size 1.27 1.27)
					(thickness 0.15)
				)
			)
		)
		(property "Value" "TP_0.75mm_SMD"
			(at 361.95 52.07 0)
			(effects
				(font
					(size 1.27 1.27)
					(thickness 0.15)
				)
				(justify left bottom)
				(hide yes)
			)
		)
		(property "Footprint" "antmicro-footprints:TP_SMD_0.75mm"
			(at 364.49 52.07 0)
			(effects
				(font
					(size 1.27 1.27)
					(thickness 0.15)
				)
				(justify left bottom)
				(hide yes)
			)
		)
		(property "Datasheet" ""
			(at 370.84 44.45 0)
			(effects
				(font
					(size 1.27 1.27)
					(thickness 0.15)
				)
				(justify left bottom)
				(hide yes)
			)
		)
		(property "Description" "SMT test point"
			(at 358.14 62.23 0)
			(effects
				(font
					(size 1.27 1.27)
				)
				(hide yes)
			)
		)
		(property "MPN" ""
			(at 369.57 51.435 0)
			(effects
				(font
					(size 1.27 1.27)
					(thickness 0.15)
				)
				(justify left bottom)
				(hide yes)
			)
		)
		(property "Manufacturer" ""
			(at 364.49 51.435 0)
			(effects
				(font
					(size 1.27 1.27)
					(thickness 0.15)
				)
				(justify left bottom)
				(hide yes)
			)
		)
		(property "Author" "Antmicro"
			(at 367.03 52.07 0)
			(effects
				(font
					(size 1.27 1.27)
					(thickness 0.15)
				)
				(justify left bottom)
				(hide yes)
			)
		)
		(property "License" "Apache-2.0"
			(at 369.57 52.07 0)
			(effects
				(font
					(size 1.27 1.27)
					(thickness 0.15)
				)
				(justify left bottom)
				(hide yes)
			)
		)
		(pin "1"
		)
		(instances
			(project "OCuLink to 10GbE adapter"
				(path ""
					(reference "TP20")
					(unit 1)
				)
			)
		)
	)
	(symbol
		(lib_id "antmicroTestPoints:TP_1mm_SMD")
		(at 391.16 233.68 0)
		(unit 1)
		(exclude_from_sim no)
		(in_bom no)
		(on_board yes)
		(dnp no)
		(fields_autoplaced yes)
		(property "Reference" "TP32"
			(at 396.24 233.68 0)
			(effects
				(font
					(size 1.27 1.27)
					(thickness 0.15)
				)
				(justify left)
			)
		)
		(property "Value" "TP_1mm_SMD"
			(at 406.4 241.3 0)
			(effects
				(font
					(size 1.27 1.27)
					(thickness 0.15)
				)
				(justify left bottom)
				(hide yes)
			)
		)
		(property "Footprint" "antmicro-footprints:TP_SMD_1mm"
			(at 406.4 243.84 0)
			(effects
				(font
					(size 1.27 1.27)
					(thickness 0.15)
				)
				(justify left bottom)
				(hide yes)
			)
		)
		(property "Datasheet" ""
			(at 408.94 246.38 0)
			(effects
				(font
					(size 1.27 1.27)
					(thickness 0.15)
				)
				(justify left bottom)
				(hide yes)
			)
		)
		(property "Description" "Test point 1mm SMD"
			(at 406.4 254 0)
			(effects
				(font
					(size 1.27 1.27)
				)
				(justify left bottom)
				(hide yes)
			)
		)
		(property "MPN" ""
			(at 391.16 233.68 0)
			(effects
				(font
					(size 1.27 1.27)
				)
				(hide yes)
			)
		)
		(property "Manufacturer" ""
			(at 391.16 233.68 0)
			(effects
				(font
					(size 1.27 1.27)
				)
				(hide yes)
			)
		)
		(property "Author" "Antmicro"
			(at 406.4 248.92 0)
			(effects
				(font
					(size 1.27 1.27)
					(thickness 0.15)
				)
				(justify left bottom)
				(hide yes)
			)
		)
		(property "License" "Apache-2.0"
			(at 406.4 251.46 0)
			(effects
				(font
					(size 1.27 1.27)
					(thickness 0.15)
				)
				(justify left bottom)
				(hide yes)
			)
		)
		(pin "1"
		)
		(instances
			(project "oculink-to-10gbe-adapter"
				(path ""
					(reference "TP32")
					(unit 1)
				)
			)
		)
	)
	(symbol
		(lib_id "antmicroCapacitors0603:C_22u_16V_0603")
		(at 354.33 76.2 90)
		(unit 1)
		(exclude_from_sim no)
		(in_bom yes)
		(on_board yes)
		(dnp no)
		(property "Reference" "C17"
			(at 356.108 72.39 90)
			(effects
				(font
					(size 1.27 1.27)
					(thickness 0.15)
				)
				(justify right)
			)
		)
		(property "Value" "C_22u_16V_0603"
			(at 364.49 55.88 0)
			(effects
				(font
					(size 1.27 1.27)
					(thickness 0.15)
				)
				(justify left bottom)
				(hide yes)
			)
		)
		(property "Footprint" "antmicro-footprints:C_0603_1608Metric_EIA"
			(at 367.03 55.88 0)
			(effects
				(font
					(size 1.27 1.27)
					(thickness 0.15)
				)
				(justify left bottom)
				(hide yes)
			)
		)
		(property "Datasheet" "https://product.samsungsem.com/mlcc/CL10A226MO7JZN.do"
			(at 369.57 55.88 0)
			(effects
				(font
					(size 1.27 1.27)
					(thickness 0.15)
				)
				(justify left bottom)
				(hide yes)
			)
		)
		(property "Description" "SMD Multilayer Ceramic Capacitor"
			(at 354.33 76.2 0)
			(effects
				(font
					(size 1.27 1.27)
				)
				(hide yes)
			)
		)
		(property "MPN" "CL10A226MO7JZNC"
			(at 372.11 55.88 0)
			(effects
				(font
					(size 1.27 1.27)
					(thickness 0.15)
				)
				(justify left bottom)
				(hide yes)
			)
		)
		(property "Manufacturer" "Samsung Electro-Mechanics"
			(at 374.65 55.88 0)
			(effects
				(font
					(size 1.27 1.27)
					(thickness 0.15)
				)
				(justify left bottom)
				(hide yes)
			)
		)
		(property "License" "Apache-2.0"
			(at 377.19 55.88 0)
			(effects
				(font
					(size 1.27 1.27)
					(thickness 0.15)
				)
				(justify left bottom)
				(hide yes)
			)
		)
		(property "Author" "Antmicro"
			(at 379.73 55.88 0)
			(effects
				(font
					(size 1.27 1.27)
					(thickness 0.15)
				)
				(justify left bottom)
				(hide yes)
			)
		)
		(property "Val" "22u"
			(at 356.108 74.93 90)
			(effects
				(font
					(size 1.27 1.27)
					(thickness 0.15)
				)
				(justify right)
			)
		)
		(property "Voltage" "16V"
			(at 356.87 76.1935 90)
			(effects
				(font
					(size 1.27 1.27)
				)
				(justify right)
				(hide yes)
			)
		)
		(property "Dielectric" ""
			(at 384.81 55.88 0)
			(effects
				(font
					(size 1.27 1.27)
				)
				(justify left bottom)
				(hide yes)
			)
		)
		(property "Public" "False"
			(at 387.35 55.88 0)
			(effects
				(font
					(size 1.27 1.27)
				)
				(justify left bottom)
				(hide yes)
			)
		)
		(pin "2"
		)
		(pin "1"
		)
		(instances
			(project "OCuLink to 10GbE adapter"
				(path ""
					(reference "C17")
					(unit 1)
				)
			)
		)
	)
	(symbol
		(lib_id "antmicropower:VCC")
		(at 217.17 175.26 0)
		(unit 1)
		(exclude_from_sim no)
		(in_bom yes)
		(on_board yes)
		(dnp no)
		(property "Reference" "#PWR0357"
			(at 217.17 179.07 0)
			(effects
				(font
					(size 1.27 1.27)
				)
				(hide yes)
			)
		)
		(property "Value" "VCC"
			(at 217.17 171.45 0)
			(effects
				(font
					(size 1.27 1.27)
				)
			)
		)
		(property "Footprint" ""
			(at 217.17 175.26 0)
			(effects
				(font
					(size 1.27 1.27)
				)
				(hide yes)
			)
		)
		(property "Datasheet" ""
			(at 217.17 175.26 0)
			(effects
				(font
					(size 1.27 1.27)
				)
				(hide yes)
			)
		)
		(property "Description" ""
			(at 217.17 181.61 0)
			(effects
				(font
					(size 1.27 1.27)
				)
				(justify left bottom)
				(hide yes)
			)
		)
		(pin "1"
		)
		(instances
			(project "oculink-to-10gbe-adapter"
				(path ""
					(reference "#PWR0357")
					(unit 1)
				)
			)
		)
	)
	(symbol
		(lib_id "antmicropower:GND")
		(at 297.18 43.18 0)
		(unit 1)
		(exclude_from_sim no)
		(in_bom yes)
		(on_board yes)
		(dnp no)
		(property "Reference" "#PWR08"
			(at 306.07 45.72 0)
			(effects
				(font
					(size 1.27 1.27)
					(thickness 0.15)
				)
				(justify left bottom)
				(hide yes)
			)
		)
		(property "Value" "GND"
			(at 297.18 46.99 0)
			(effects
				(font
					(size 1.27 1.27)
					(thickness 0.15)
				)
			)
		)
		(property "Footprint" ""
			(at 306.07 50.8 0)
			(effects
				(font
					(size 1.27 1.27)
					(thickness 0.15)
				)
				(justify left bottom)
				(hide yes)
			)
		)
		(property "Datasheet" ""
			(at 306.07 55.88 0)
			(effects
				(font
					(size 1.27 1.27)
					(thickness 0.15)
				)
				(justify left bottom)
				(hide yes)
			)
		)
		(property "Description" ""
			(at 297.18 43.18 0)
			(effects
				(font
					(size 1.27 1.27)
				)
				(hide yes)
			)
		)
		(property "Author" "Antmicro"
			(at 306.07 50.8 0)
			(effects
				(font
					(size 1.27 1.27)
					(thickness 0.15)
				)
				(justify left bottom)
				(hide yes)
			)
		)
		(property "License" "Apache-2.0"
			(at 306.07 53.34 0)
			(effects
				(font
					(size 1.27 1.27)
					(thickness 0.15)
				)
				(justify left bottom)
				(hide yes)
			)
		)
		(pin "1"
		)
		(instances
			(project "OCuLink to 10GbE adapter"
				(path ""
					(reference "#PWR08")
					(unit 1)
				)
			)
		)
	)
	(symbol
		(lib_id "antmicropower:GND")
		(at 237.49 157.48 0)
		(unit 1)
		(exclude_from_sim no)
		(in_bom yes)
		(on_board yes)
		(dnp no)
		(property "Reference" "#PWR039"
			(at 246.38 160.02 0)
			(effects
				(font
					(size 1.27 1.27)
					(thickness 0.15)
				)
				(justify left bottom)
				(hide yes)
			)
		)
		(property "Value" "GND"
			(at 237.49 161.29 0)
			(effects
				(font
					(size 1.27 1.27)
					(thickness 0.15)
				)
			)
		)
		(property "Footprint" ""
			(at 246.38 165.1 0)
			(effects
				(font
					(size 1.27 1.27)
					(thickness 0.15)
				)
				(justify left bottom)
				(hide yes)
			)
		)
		(property "Datasheet" ""
			(at 246.38 170.18 0)
			(effects
				(font
					(size 1.27 1.27)
					(thickness 0.15)
				)
				(justify left bottom)
				(hide yes)
			)
		)
		(property "Description" ""
			(at 237.49 157.48 0)
			(effects
				(font
					(size 1.27 1.27)
				)
				(hide yes)
			)
		)
		(property "Author" "Antmicro"
			(at 246.38 165.1 0)
			(effects
				(font
					(size 1.27 1.27)
					(thickness 0.15)
				)
				(justify left bottom)
				(hide yes)
			)
		)
		(property "License" "Apache-2.0"
			(at 246.38 167.64 0)
			(effects
				(font
					(size 1.27 1.27)
					(thickness 0.15)
				)
				(justify left bottom)
				(hide yes)
			)
		)
		(pin "1"
		)
		(instances
			(project "OCuLink to 10GbE adapter"
				(path ""
					(reference "#PWR039")
					(unit 1)
				)
			)
		)
	)
	(symbol
		(lib_id "antmicropower:VCC")
		(at 387.35 226.06 90)
		(unit 1)
		(exclude_from_sim no)
		(in_bom yes)
		(on_board yes)
		(dnp no)
		(fields_autoplaced yes)
		(property "Reference" "#PWR0304"
			(at 391.16 226.06 0)
			(effects
				(font
					(size 1.27 1.27)
				)
				(hide yes)
			)
		)
		(property "Value" "VCC"
			(at 383.54 226.0599 90)
			(effects
				(font
					(size 1.27 1.27)
				)
				(justify left)
			)
		)
		(property "Footprint" ""
			(at 387.35 226.06 0)
			(effects
				(font
					(size 1.27 1.27)
				)
				(hide yes)
			)
		)
		(property "Datasheet" ""
			(at 387.35 226.06 0)
			(effects
				(font
					(size 1.27 1.27)
				)
				(hide yes)
			)
		)
		(property "Description" ""
			(at 393.7 226.06 0)
			(effects
				(font
					(size 1.27 1.27)
				)
				(justify left bottom)
				(hide yes)
			)
		)
		(pin "1"
		)
		(instances
			(project "oculink-to-10gbe-adapter"
				(path ""
					(reference "#PWR0304")
					(unit 1)
				)
			)
		)
	)
	(symbol
		(lib_id "antmicroCapacitors0603:C_22u_16V_0603")
		(at 364.49 114.3 90)
		(unit 1)
		(exclude_from_sim no)
		(in_bom yes)
		(on_board yes)
		(dnp no)
		(property "Reference" "C206"
			(at 366.268 110.49 90)
			(effects
				(font
					(size 1.27 1.27)
					(thickness 0.15)
				)
				(justify right)
			)
		)
		(property "Value" "C_22u_16V_0603"
			(at 374.65 93.98 0)
			(effects
				(font
					(size 1.27 1.27)
					(thickness 0.15)
				)
				(justify left bottom)
				(hide yes)
			)
		)
		(property "Footprint" "antmicro-footprints:C_0603_1608Metric_EIA"
			(at 377.19 93.98 0)
			(effects
				(font
					(size 1.27 1.27)
					(thickness 0.15)
				)
				(justify left bottom)
				(hide yes)
			)
		)
		(property "Datasheet" "https://product.samsungsem.com/mlcc/CL10A226MO7JZN.do"
			(at 379.73 93.98 0)
			(effects
				(font
					(size 1.27 1.27)
					(thickness 0.15)
				)
				(justify left bottom)
				(hide yes)
			)
		)
		(property "Description" "SMD Multilayer Ceramic Capacitor"
			(at 364.49 114.3 0)
			(effects
				(font
					(size 1.27 1.27)
				)
				(hide yes)
			)
		)
		(property "MPN" "CL10A226MO7JZNC"
			(at 382.27 93.98 0)
			(effects
				(font
					(size 1.27 1.27)
					(thickness 0.15)
				)
				(justify left bottom)
				(hide yes)
			)
		)
		(property "Manufacturer" "Samsung Electro-Mechanics"
			(at 384.81 93.98 0)
			(effects
				(font
					(size 1.27 1.27)
					(thickness 0.15)
				)
				(justify left bottom)
				(hide yes)
			)
		)
		(property "License" "Apache-2.0"
			(at 387.35 93.98 0)
			(effects
				(font
					(size 1.27 1.27)
					(thickness 0.15)
				)
				(justify left bottom)
				(hide yes)
			)
		)
		(property "Author" "Antmicro"
			(at 389.89 93.98 0)
			(effects
				(font
					(size 1.27 1.27)
					(thickness 0.15)
				)
				(justify left bottom)
				(hide yes)
			)
		)
		(property "Val" "22u"
			(at 366.268 113.03 90)
			(effects
				(font
					(size 1.27 1.27)
					(thickness 0.15)
				)
				(justify right)
			)
		)
		(property "Voltage" "16V"
			(at 367.03 114.2935 90)
			(effects
				(font
					(size 1.27 1.27)
				)
				(justify right)
				(hide yes)
			)
		)
		(property "Dielectric" ""
			(at 394.97 93.98 0)
			(effects
				(font
					(size 1.27 1.27)
				)
				(justify left bottom)
				(hide yes)
			)
		)
		(property "Public" "False"
			(at 397.51 93.98 0)
			(effects
				(font
					(size 1.27 1.27)
				)
				(justify left bottom)
				(hide yes)
			)
		)
		(pin "2"
		)
		(pin "1"
		)
		(instances
			(project "OCuLink to 10GbE adapter"
				(path ""
					(reference "C206")
					(unit 1)
				)
			)
		)
	)
	(symbol
		(lib_id "antmicropower:GND")
		(at 332.74 81.28 0)
		(unit 1)
		(exclude_from_sim no)
		(in_bom yes)
		(on_board yes)
		(dnp no)
		(property "Reference" "#PWR019"
			(at 341.63 83.82 0)
			(effects
				(font
					(size 1.27 1.27)
					(thickness 0.15)
				)
				(justify left bottom)
				(hide yes)
			)
		)
		(property "Value" "GND"
			(at 332.74 85.09 0)
			(effects
				(font
					(size 1.27 1.27)
					(thickness 0.15)
				)
			)
		)
		(property "Footprint" ""
			(at 341.63 88.9 0)
			(effects
				(font
					(size 1.27 1.27)
					(thickness 0.15)
				)
				(justify left bottom)
				(hide yes)
			)
		)
		(property "Datasheet" ""
			(at 341.63 93.98 0)
			(effects
				(font
					(size 1.27 1.27)
					(thickness 0.15)
				)
				(justify left bottom)
				(hide yes)
			)
		)
		(property "Description" ""
			(at 332.74 81.28 0)
			(effects
				(font
					(size 1.27 1.27)
				)
				(hide yes)
			)
		)
		(property "Author" "Antmicro"
			(at 341.63 88.9 0)
			(effects
				(font
					(size 1.27 1.27)
					(thickness 0.15)
				)
				(justify left bottom)
				(hide yes)
			)
		)
		(property "License" "Apache-2.0"
			(at 341.63 91.44 0)
			(effects
				(font
					(size 1.27 1.27)
					(thickness 0.15)
				)
				(justify left bottom)
				(hide yes)
			)
		)
		(pin "1"
		)
		(instances
			(project "OCuLink to 10GbE adapter"
				(path ""
					(reference "#PWR019")
					(unit 1)
				)
			)
		)
	)
	(symbol
		(lib_id "antmicroLEDIndicationDiscrete:LED_G_0603_LG_L29K-G2J1-24-Z")
		(at 279.4 223.52 90)
		(unit 1)
		(exclude_from_sim no)
		(in_bom yes)
		(on_board yes)
		(dnp no)
		(property "Reference" "D20"
			(at 280.67 219.71 90)
			(effects
				(font
					(size 1.27 1.27)
					(thickness 0.15)
				)
				(justify right)
			)
		)
		(property "Value" "LED_G_0603_LG_L29K-G2J1-24-Z"
			(at 287.02 203.2 0)
			(effects
				(font
					(size 1.27 1.27)
					(thickness 0.15)
				)
				(justify left bottom)
				(hide yes)
			)
		)
		(property "Footprint" "antmicro-footprints:LED_0603_1608Metric_G"
			(at 289.56 203.2 0)
			(effects
				(font
					(size 1.27 1.27)
					(thickness 0.15)
				)
				(justify left bottom)
				(hide yes)
			)
		)
		(property "Datasheet" "https://look.ams-osram.com/m/19ee86b3ae0ee95b/original/LG-L29K.pdf"
			(at 292.1 203.2 0)
			(effects
				(font
					(size 1.27 1.27)
					(thickness 0.15)
				)
				(justify left bottom)
				(hide yes)
			)
		)
		(property "Description" "LED, Green, SMD, 0603, 20 mA, 1.7 V, 570 nm"
			(at 279.4 223.52 0)
			(effects
				(font
					(size 1.27 1.27)
				)
				(hide yes)
			)
		)
		(property "MPN" "LG L29K-G2J1-24-Z"
			(at 294.64 203.2 0)
			(effects
				(font
					(size 1.27 1.27)
					(thickness 0.15)
				)
				(justify left bottom)
				(hide yes)
			)
		)
		(property "Manufacturer" "OSRAM"
			(at 297.18 203.2 0)
			(effects
				(font
					(size 1.27 1.27)
					(thickness 0.15)
				)
				(justify left bottom)
				(hide yes)
			)
		)
		(property "Color" "Green"
			(at 280.67 222.2499 90)
			(effects
				(font
					(size 1.27 1.27)
				)
				(justify right)
			)
		)
		(property "Author" "Antmicro"
			(at 299.72 203.2 0)
			(effects
				(font
					(size 1.27 1.27)
					(thickness 0.15)
				)
				(justify left bottom)
				(hide yes)
			)
		)
		(property "License" "Apache-2.0"
			(at 302.26 203.2 0)
			(effects
				(font
					(size 1.27 1.27)
					(thickness 0.15)
				)
				(justify left bottom)
				(hide yes)
			)
		)
		(pin "2"
		)
		(pin "1"
		)
		(instances
			(project "oculink-to-10gbe-adapter"
				(path ""
					(reference "D20")
					(unit 1)
				)
			)
		)
	)
	(symbol
		(lib_id "antmicroLEDIndicationDiscrete:LED_G_0603_LG_L29K-G2J1-24-Z")
		(at 228.6 223.52 90)
		(unit 1)
		(exclude_from_sim no)
		(in_bom yes)
		(on_board yes)
		(dnp no)
		(property "Reference" "D18"
			(at 229.87 219.71 90)
			(effects
				(font
					(size 1.27 1.27)
					(thickness 0.15)
				)
				(justify right)
			)
		)
		(property "Value" "LED_G_0603_LG_L29K-G2J1-24-Z"
			(at 236.22 203.2 0)
			(effects
				(font
					(size 1.27 1.27)
					(thickness 0.15)
				)
				(justify left bottom)
				(hide yes)
			)
		)
		(property "Footprint" "antmicro-footprints:LED_0603_1608Metric_G"
			(at 238.76 203.2 0)
			(effects
				(font
					(size 1.27 1.27)
					(thickness 0.15)
				)
				(justify left bottom)
				(hide yes)
			)
		)
		(property "Datasheet" "https://look.ams-osram.com/m/19ee86b3ae0ee95b/original/LG-L29K.pdf"
			(at 241.3 203.2 0)
			(effects
				(font
					(size 1.27 1.27)
					(thickness 0.15)
				)
				(justify left bottom)
				(hide yes)
			)
		)
		(property "Description" "LED, Green, SMD, 0603, 20 mA, 1.7 V, 570 nm"
			(at 228.6 223.52 0)
			(effects
				(font
					(size 1.27 1.27)
				)
				(hide yes)
			)
		)
		(property "MPN" "LG L29K-G2J1-24-Z"
			(at 243.84 203.2 0)
			(effects
				(font
					(size 1.27 1.27)
					(thickness 0.15)
				)
				(justify left bottom)
				(hide yes)
			)
		)
		(property "Manufacturer" "OSRAM"
			(at 246.38 203.2 0)
			(effects
				(font
					(size 1.27 1.27)
					(thickness 0.15)
				)
				(justify left bottom)
				(hide yes)
			)
		)
		(property "Color" "Green"
			(at 229.87 222.2499 90)
			(effects
				(font
					(size 1.27 1.27)
				)
				(justify right)
			)
		)
		(property "Author" "Antmicro"
			(at 248.92 203.2 0)
			(effects
				(font
					(size 1.27 1.27)
					(thickness 0.15)
				)
				(justify left bottom)
				(hide yes)
			)
		)
		(property "License" "Apache-2.0"
			(at 251.46 203.2 0)
			(effects
				(font
					(size 1.27 1.27)
					(thickness 0.15)
				)
				(justify left bottom)
				(hide yes)
			)
		)
		(pin "2"
		)
		(pin "1"
		)
		(instances
			(project "oculink-to-10gbe-adapter"
				(path ""
					(reference "D18")
					(unit 1)
				)
			)
		)
	)
	(symbol
		(lib_id "antmicropower:GND")
		(at 247.65 43.18 0)
		(unit 1)
		(exclude_from_sim no)
		(in_bom yes)
		(on_board yes)
		(dnp no)
		(property "Reference" "#PWR07"
			(at 256.54 45.72 0)
			(effects
				(font
					(size 1.27 1.27)
					(thickness 0.15)
				)
				(justify left bottom)
				(hide yes)
			)
		)
		(property "Value" "GND"
			(at 247.65 46.99 0)
			(effects
				(font
					(size 1.27 1.27)
					(thickness 0.15)
				)
			)
		)
		(property "Footprint" ""
			(at 256.54 50.8 0)
			(effects
				(font
					(size 1.27 1.27)
					(thickness 0.15)
				)
				(justify left bottom)
				(hide yes)
			)
		)
		(property "Datasheet" ""
			(at 256.54 55.88 0)
			(effects
				(font
					(size 1.27 1.27)
					(thickness 0.15)
				)
				(justify left bottom)
				(hide yes)
			)
		)
		(property "Description" ""
			(at 247.65 43.18 0)
			(effects
				(font
					(size 1.27 1.27)
				)
				(hide yes)
			)
		)
		(property "Author" "Antmicro"
			(at 256.54 50.8 0)
			(effects
				(font
					(size 1.27 1.27)
					(thickness 0.15)
				)
				(justify left bottom)
				(hide yes)
			)
		)
		(property "License" "Apache-2.0"
			(at 256.54 53.34 0)
			(effects
				(font
					(size 1.27 1.27)
					(thickness 0.15)
				)
				(justify left bottom)
				(hide yes)
			)
		)
		(pin "1"
		)
		(instances
			(project "OCuLink to 10GbE adapter"
				(path ""
					(reference "#PWR07")
					(unit 1)
				)
			)
		)
	)
	(symbol
		(lib_id "antmicropower:GND")
		(at 247.65 81.28 0)
		(unit 1)
		(exclude_from_sim no)
		(in_bom yes)
		(on_board yes)
		(dnp no)
		(property "Reference" "#PWR017"
			(at 256.54 83.82 0)
			(effects
				(font
					(size 1.27 1.27)
					(thickness 0.15)
				)
				(justify left bottom)
				(hide yes)
			)
		)
		(property "Value" "GND"
			(at 247.65 85.09 0)
			(effects
				(font
					(size 1.27 1.27)
					(thickness 0.15)
				)
			)
		)
		(property "Footprint" ""
			(at 256.54 88.9 0)
			(effects
				(font
					(size 1.27 1.27)
					(thickness 0.15)
				)
				(justify left bottom)
				(hide yes)
			)
		)
		(property "Datasheet" ""
			(at 256.54 93.98 0)
			(effects
				(font
					(size 1.27 1.27)
					(thickness 0.15)
				)
				(justify left bottom)
				(hide yes)
			)
		)
		(property "Description" ""
			(at 247.65 81.28 0)
			(effects
				(font
					(size 1.27 1.27)
				)
				(hide yes)
			)
		)
		(property "Author" "Antmicro"
			(at 256.54 88.9 0)
			(effects
				(font
					(size 1.27 1.27)
					(thickness 0.15)
				)
				(justify left bottom)
				(hide yes)
			)
		)
		(property "License" "Apache-2.0"
			(at 256.54 91.44 0)
			(effects
				(font
					(size 1.27 1.27)
					(thickness 0.15)
				)
				(justify left bottom)
				(hide yes)
			)
		)
		(pin "1"
		)
		(instances
			(project "OCuLink to 10GbE adapter"
				(path ""
					(reference "#PWR017")
					(unit 1)
				)
			)
		)
	)
	(symbol
		(lib_id "antmicroResistors0402:R_100k_0402")
		(at 256.54 190.5 270)
		(mirror x)
		(unit 1)
		(exclude_from_sim no)
		(in_bom yes)
		(on_board yes)
		(dnp no)
		(property "Reference" "R31"
			(at 255.27 186.69 90)
			(effects
				(font
					(size 1.27 1.27)
					(thickness 0.15)
				)
				(justify right)
			)
		)
		(property "Value" "R_100k_0402"
			(at 243.84 170.18 0)
			(effects
				(font
					(size 1.27 1.27)
					(thickness 0.15)
				)
				(justify left bottom)
				(hide yes)
			)
		)
		(property "Footprint" "antmicro-footprints:R_0402_1005Metric"
			(at 241.3 170.18 0)
			(effects
				(font
					(size 1.27 1.27)
					(thickness 0.15)
				)
				(justify left bottom)
				(hide yes)
			)
		)
		(property "Datasheet" "https://www.bourns.com/docs/product-datasheets/cr.pdf"
			(at 238.76 170.18 0)
			(effects
				(font
					(size 1.27 1.27)
					(thickness 0.15)
				)
				(justify left bottom)
				(hide yes)
			)
		)
		(property "Description" "SMD Chip Resistor, 100 kohm, ± 1%, 62.5 mW, 0402 [1005 Metric], Thick Film, General Purpose"
			(at 226.06 170.18 0)
			(effects
				(font
					(size 1.27 1.27)
				)
				(justify left bottom)
				(hide yes)
			)
		)
		(property "MPN" "CR0402-FX-1003GLF"
			(at 236.22 170.18 0)
			(effects
				(font
					(size 1.27 1.27)
					(thickness 0.15)
				)
				(justify left bottom)
				(hide yes)
			)
		)
		(property "Manufacturer" "Bourns"
			(at 233.68 170.18 0)
			(effects
				(font
					(size 1.27 1.27)
					(thickness 0.15)
				)
				(justify left bottom)
				(hide yes)
			)
		)
		(property "License" "Apache-2.0"
			(at 231.14 170.18 0)
			(effects
				(font
					(size 1.27 1.27)
					(thickness 0.15)
				)
				(justify left bottom)
				(hide yes)
			)
		)
		(property "Author" "Antmicro"
			(at 228.6 170.18 0)
			(effects
				(font
					(size 1.27 1.27)
					(thickness 0.15)
				)
				(justify left bottom)
				(hide yes)
			)
		)
		(property "Val" "100k"
			(at 255.27 189.23 90)
			(effects
				(font
					(size 1.27 1.27)
					(thickness 0.15)
				)
				(justify right)
			)
		)
		(property "Tolerance" "1%"
			(at 246.38 170.18 0)
			(effects
				(font
					(size 1.27 1.27)
				)
				(justify left bottom)
				(hide yes)
			)
		)
		(pin "1"
		)
		(pin "2"
		)
		(instances
			(project "OCuLink to 10GbE adapter"
				(path ""
					(reference "R31")
					(unit 1)
				)
			)
		)
	)
	(symbol
		(lib_id "antmicropower:GND")
		(at 297.18 119.38 0)
		(unit 1)
		(exclude_from_sim no)
		(in_bom yes)
		(on_board yes)
		(dnp no)
		(property "Reference" "#PWR031"
			(at 306.07 121.92 0)
			(effects
				(font
					(size 1.27 1.27)
					(thickness 0.15)
				)
				(justify left bottom)
				(hide yes)
			)
		)
		(property "Value" "GND"
			(at 297.18 123.19 0)
			(effects
				(font
					(size 1.27 1.27)
					(thickness 0.15)
				)
			)
		)
		(property "Footprint" ""
			(at 306.07 127 0)
			(effects
				(font
					(size 1.27 1.27)
					(thickness 0.15)
				)
				(justify left bottom)
				(hide yes)
			)
		)
		(property "Datasheet" ""
			(at 306.07 132.08 0)
			(effects
				(font
					(size 1.27 1.27)
					(thickness 0.15)
				)
				(justify left bottom)
				(hide yes)
			)
		)
		(property "Description" ""
			(at 297.18 119.38 0)
			(effects
				(font
					(size 1.27 1.27)
				)
				(hide yes)
			)
		)
		(property "Author" "Antmicro"
			(at 306.07 127 0)
			(effects
				(font
					(size 1.27 1.27)
					(thickness 0.15)
				)
				(justify left bottom)
				(hide yes)
			)
		)
		(property "License" "Apache-2.0"
			(at 306.07 129.54 0)
			(effects
				(font
					(size 1.27 1.27)
					(thickness 0.15)
				)
				(justify left bottom)
				(hide yes)
			)
		)
		(pin "1"
		)
		(instances
			(project "OCuLink to 10GbE adapter"
				(path ""
					(reference "#PWR031")
					(unit 1)
				)
			)
		)
	)
	(symbol
		(lib_id "antmicropower:GND")
		(at 76.2 172.72 0)
		(unit 1)
		(exclude_from_sim no)
		(in_bom yes)
		(on_board yes)
		(dnp no)
		(property "Reference" "#PWR048"
			(at 85.09 175.26 0)
			(effects
				(font
					(size 1.27 1.27)
					(thickness 0.15)
				)
				(justify left bottom)
				(hide yes)
			)
		)
		(property "Value" "GND"
			(at 76.2 176.53 0)
			(effects
				(font
					(size 1.27 1.27)
					(thickness 0.15)
				)
			)
		)
		(property "Footprint" ""
			(at 85.09 180.34 0)
			(effects
				(font
					(size 1.27 1.27)
					(thickness 0.15)
				)
				(justify left bottom)
				(hide yes)
			)
		)
		(property "Datasheet" ""
			(at 85.09 185.42 0)
			(effects
				(font
					(size 1.27 1.27)
					(thickness 0.15)
				)
				(justify left bottom)
				(hide yes)
			)
		)
		(property "Description" ""
			(at 76.2 172.72 0)
			(effects
				(font
					(size 1.27 1.27)
				)
				(hide yes)
			)
		)
		(property "Author" "Antmicro"
			(at 85.09 180.34 0)
			(effects
				(font
					(size 1.27 1.27)
					(thickness 0.15)
				)
				(justify left bottom)
				(hide yes)
			)
		)
		(property "License" "Apache-2.0"
			(at 85.09 182.88 0)
			(effects
				(font
					(size 1.27 1.27)
					(thickness 0.15)
				)
				(justify left bottom)
				(hide yes)
			)
		)
		(pin "1"
		)
		(instances
			(project "OCuLink to 10GbE adapter"
				(path ""
					(reference "#PWR048")
					(unit 1)
				)
			)
		)
	)
	(symbol
		(lib_id "antmicroResistors0603:R_0R_22.4A_0603")
		(at 379.73 63.5 0)
		(unit 1)
		(exclude_from_sim no)
		(in_bom yes)
		(on_board yes)
		(dnp no)
		(property "Reference" "R8"
			(at 379.73 62.23 0)
			(effects
				(font
					(size 1.27 1.27)
					(thickness 0.15)
				)
				(justify right)
			)
		)
		(property "Value" "R_0R_22.4A_0603"
			(at 394.97 68.58 0)
			(effects
				(font
					(size 1.27 1.27)
					(thickness 0.15)
				)
				(justify left bottom)
				(hide yes)
			)
		)
		(property "Footprint" "antmicro-footprints:R_0603_1608Metric"
			(at 394.97 73.66 0)
			(effects
				(font
					(size 1.27 1.27)
					(thickness 0.15)
				)
				(justify left bottom)
				(hide yes)
			)
		)
		(property "Datasheet" "https://fscdn.rohm.com/en/products/databook/datasheet/passive/resistor/chip_resistor/pmr-jpw-e.pdf"
			(at 394.97 76.2 0)
			(effects
				(font
					(size 1.27 1.27)
					(thickness 0.15)
				)
				(justify left bottom)
				(hide yes)
			)
		)
		(property "Description" "SMD Chip Resistor"
			(at 394.97 91.44 0)
			(effects
				(font
					(size 1.27 1.27)
				)
				(justify left bottom)
				(hide yes)
			)
		)
		(property "MPN" "PMR03EZPJ000"
			(at 394.97 78.74 0)
			(effects
				(font
					(size 1.27 1.27)
					(thickness 0.15)
				)
				(justify left bottom)
				(hide yes)
			)
		)
		(property "Manufacturer" "ROHM Semiconductor"
			(at 394.97 81.28 0)
			(effects
				(font
					(size 1.27 1.27)
					(thickness 0.15)
				)
				(justify left bottom)
				(hide yes)
			)
		)
		(property "Val" "0R"
			(at 384.81 62.23 0)
			(effects
				(font
					(size 1.27 1.27)
					(thickness 0.15)
				)
				(justify left)
			)
		)
		(property "Max. Curr." "22.4A"
			(at 382.27 66.04 0)
			(effects
				(font
					(size 1.27 1.27)
					(thickness 0.15)
				)
			)
		)
		(property "Author" "Antmicro"
			(at 394.97 86.36 0)
			(effects
				(font
					(size 1.27 1.27)
					(thickness 0.15)
				)
				(justify left bottom)
				(hide yes)
			)
		)
		(property "License" "Apache-2.0"
			(at 394.97 88.9 0)
			(effects
				(font
					(size 1.27 1.27)
					(thickness 0.15)
				)
				(justify left bottom)
				(hide yes)
			)
		)
		(property "Tolerance" "template_tolerance"
			(at 400.05 73.66 0)
			(effects
				(font
					(size 1.27 1.27)
				)
				(justify left bottom)
				(hide yes)
			)
		)
		(pin "1"
		)
		(pin "2"
		)
		(instances
			(project "OCuLink to 10GbE adapter"
				(path ""
					(reference "R8")
					(unit 1)
				)
			)
		)
	)
	(symbol
		(lib_id "antmicroTransistorsBipolarSingle:DTC014T_SOT-416")
		(at 271.78 238.76 0)
		(unit 1)
		(exclude_from_sim no)
		(in_bom yes)
		(on_board yes)
		(dnp no)
		(property "Reference" "Q9"
			(at 281.178 240.03 0)
			(effects
				(font
					(size 1.27 1.27)
					(thickness 0.15)
				)
				(justify left)
			)
		)
		(property "Value" "DTC014T_SOT-416"
			(at 297.18 246.38 0)
			(effects
				(font
					(size 1.27 1.27)
					(thickness 0.15)
				)
				(justify left bottom)
				(hide yes)
			)
		)
		(property "Footprint" "antmicro-footprints:SOT-416"
			(at 297.18 248.92 0)
			(effects
				(font
					(size 1.27 1.27)
					(thickness 0.15)
				)
				(justify left bottom)
				(hide yes)
			)
		)
		(property "Datasheet" "https://www.rohm.com/datasheet?p=DTC014TEB&dist=Mouser&media=referral&source=mouser.com&campaign=Mouser"
			(at 297.18 251.46 0)
			(effects
				(font
					(size 1.27 1.27)
					(thickness 0.15)
				)
				(justify left bottom)
				(hide yes)
			)
		)
		(property "Description" "Bipolar (BJT) Single Transistor with built-in base resistor, NPN, 50V, 100mA, 150mW, SOT-416FL, Surface Mount"
			(at 297.18 264.16 0)
			(effects
				(font
					(size 1.27 1.27)
				)
				(justify left bottom)
				(hide yes)
			)
		)
		(property "Manufacturer" "ROHM Semiconductor"
			(at 297.18 254 0)
			(effects
				(font
					(size 1.27 1.27)
					(thickness 0.15)
				)
				(justify left bottom)
				(hide yes)
			)
		)
		(property "MPN" "DTC014TEBTL"
			(at 281.178 242.57 0)
			(effects
				(font
					(size 1.27 1.27)
					(thickness 0.15)
				)
				(justify left)
			)
		)
		(property "Author" "Antmicro"
			(at 297.18 259.08 0)
			(effects
				(font
					(size 1.27 1.27)
					(thickness 0.15)
				)
				(justify left bottom)
				(hide yes)
			)
		)
		(property "License" "Apache-2.0"
			(at 297.18 261.62 0)
			(effects
				(font
					(size 1.27 1.27)
					(thickness 0.15)
				)
				(justify left bottom)
				(hide yes)
			)
		)
		(pin "1"
		)
		(pin "2"
		)
		(pin "3"
		)
		(instances
			(project "oculink-to-10gbe-adapter"
				(path ""
					(reference "Q9")
					(unit 1)
				)
			)
		)
	)
	(symbol
		(lib_id "antmicropower:GND")
		(at 354.33 81.28 0)
		(unit 1)
		(exclude_from_sim no)
		(in_bom yes)
		(on_board yes)
		(dnp no)
		(property "Reference" "#PWR021"
			(at 363.22 83.82 0)
			(effects
				(font
					(size 1.27 1.27)
					(thickness 0.15)
				)
				(justify left bottom)
				(hide yes)
			)
		)
		(property "Value" "GND"
			(at 354.33 85.09 0)
			(effects
				(font
					(size 1.27 1.27)
					(thickness 0.15)
				)
			)
		)
		(property "Footprint" ""
			(at 363.22 88.9 0)
			(effects
				(font
					(size 1.27 1.27)
					(thickness 0.15)
				)
				(justify left bottom)
				(hide yes)
			)
		)
		(property "Datasheet" ""
			(at 363.22 93.98 0)
			(effects
				(font
					(size 1.27 1.27)
					(thickness 0.15)
				)
				(justify left bottom)
				(hide yes)
			)
		)
		(property "Description" ""
			(at 354.33 81.28 0)
			(effects
				(font
					(size 1.27 1.27)
				)
				(hide yes)
			)
		)
		(property "Author" "Antmicro"
			(at 363.22 88.9 0)
			(effects
				(font
					(size 1.27 1.27)
					(thickness 0.15)
				)
				(justify left bottom)
				(hide yes)
			)
		)
		(property "License" "Apache-2.0"
			(at 363.22 91.44 0)
			(effects
				(font
					(size 1.27 1.27)
					(thickness 0.15)
				)
				(justify left bottom)
				(hide yes)
			)
		)
		(pin "1"
		)
		(instances
			(project "OCuLink to 10GbE adapter"
				(path ""
					(reference "#PWR021")
					(unit 1)
				)
			)
		)
	)
	(symbol
		(lib_id "antmicropower:GND")
		(at 364.49 119.38 0)
		(unit 1)
		(exclude_from_sim no)
		(in_bom yes)
		(on_board yes)
		(dnp no)
		(property "Reference" "#PWR0335"
			(at 373.38 121.92 0)
			(effects
				(font
					(size 1.27 1.27)
					(thickness 0.15)
				)
				(justify left bottom)
				(hide yes)
			)
		)
		(property "Value" "GND"
			(at 364.49 123.19 0)
			(effects
				(font
					(size 1.27 1.27)
					(thickness 0.15)
				)
			)
		)
		(property "Footprint" ""
			(at 373.38 127 0)
			(effects
				(font
					(size 1.27 1.27)
					(thickness 0.15)
				)
				(justify left bottom)
				(hide yes)
			)
		)
		(property "Datasheet" ""
			(at 373.38 132.08 0)
			(effects
				(font
					(size 1.27 1.27)
					(thickness 0.15)
				)
				(justify left bottom)
				(hide yes)
			)
		)
		(property "Description" ""
			(at 364.49 119.38 0)
			(effects
				(font
					(size 1.27 1.27)
				)
				(hide yes)
			)
		)
		(property "Author" "Antmicro"
			(at 373.38 127 0)
			(effects
				(font
					(size 1.27 1.27)
					(thickness 0.15)
				)
				(justify left bottom)
				(hide yes)
			)
		)
		(property "License" "Apache-2.0"
			(at 373.38 129.54 0)
			(effects
				(font
					(size 1.27 1.27)
					(thickness 0.15)
				)
				(justify left bottom)
				(hide yes)
			)
		)
		(pin "1"
		)
		(instances
			(project "OCuLink to 10GbE adapter"
				(path ""
					(reference "#PWR0335")
					(unit 1)
				)
			)
		)
	)
	(symbol
		(lib_id "antmicroCapacitors0402:C_33p_0402")
		(at 327.66 185.42 270)
		(mirror x)
		(unit 1)
		(exclude_from_sim no)
		(in_bom no)
		(on_board yes)
		(dnp yes)
		(property "Reference" "C39"
			(at 325.882 181.61 90)
			(effects
				(font
					(size 1.27 1.27)
					(thickness 0.15)
				)
				(justify right)
			)
		)
		(property "Value" "C_33p_0402"
			(at 317.5 165.1 0)
			(effects
				(font
					(size 1.27 1.27)
					(thickness 0.15)
				)
				(justify left bottom)
				(hide yes)
			)
		)
		(property "Footprint" "antmicro-footprints:C_0402_1005Metric"
			(at 314.96 165.1 0)
			(effects
				(font
					(size 1.27 1.27)
					(thickness 0.15)
				)
				(justify left bottom)
				(hide yes)
			)
		)
		(property "Datasheet" "https://spicat.kyocera-avx.com/product/mlcc/chartview/04025A330FAT2A/"
			(at 312.42 165.1 0)
			(effects
				(font
					(size 1.27 1.27)
					(thickness 0.15)
				)
				(justify left bottom)
				(hide yes)
			)
		)
		(property "Description" "SMD Multilayer Ceramic Capacitor, 33 pF, 50 V, 0402 [1005 Metric], ± 5%, C0G / NP0, MC"
			(at 294.64 165.1 0)
			(effects
				(font
					(size 1.27 1.27)
				)
				(justify left bottom)
				(hide yes)
			)
		)
		(property "MPN" "04025A330FAT2A"
			(at 309.88 165.1 0)
			(effects
				(font
					(size 1.27 1.27)
					(thickness 0.15)
				)
				(justify left bottom)
				(hide yes)
			)
		)
		(property "Manufacturer" "KYOCERA AVX"
			(at 307.34 165.1 0)
			(effects
				(font
					(size 1.27 1.27)
					(thickness 0.15)
				)
				(justify left bottom)
				(hide yes)
			)
		)
		(property "License" "Apache-2.0"
			(at 304.8 165.1 0)
			(effects
				(font
					(size 1.27 1.27)
					(thickness 0.15)
				)
				(justify left bottom)
				(hide yes)
			)
		)
		(property "Author" "Antmicro"
			(at 302.26 165.1 0)
			(effects
				(font
					(size 1.27 1.27)
					(thickness 0.15)
				)
				(justify left bottom)
				(hide yes)
			)
		)
		(property "Val" "33p"
			(at 325.882 184.15 90)
			(effects
				(font
					(size 1.27 1.27)
					(thickness 0.15)
				)
				(justify right)
			)
		)
		(property "Voltage" ""
			(at 299.72 165.1 0)
			(effects
				(font
					(size 1.27 1.27)
				)
				(justify left bottom)
				(hide yes)
			)
		)
		(property "Dielectric" ""
			(at 297.18 165.1 0)
			(effects
				(font
					(size 1.27 1.27)
				)
				(justify left bottom)
				(hide yes)
			)
		)
		(pin "2"
		)
		(pin "1"
		)
		(instances
			(project "OCuLink to 10GbE adapter"
				(path ""
					(reference "C39")
					(unit 1)
				)
			)
		)
	)
	(symbol
		(lib_id "antmicroCapacitors0402:C_100n_0402")
		(at 237.49 38.1 270)
		(mirror x)
		(unit 1)
		(exclude_from_sim no)
		(in_bom yes)
		(on_board yes)
		(dnp no)
		(property "Reference" "C5"
			(at 235.712 34.29 90)
			(effects
				(font
					(size 1.27 1.27)
					(thickness 0.15)
				)
				(justify right)
			)
		)
		(property "Value" "C_100n_0402"
			(at 227.33 17.78 0)
			(effects
				(font
					(size 1.27 1.27)
					(thickness 0.15)
				)
				(justify left bottom)
				(hide yes)
			)
		)
		(property "Footprint" "antmicro-footprints:C_0402_1005Metric"
			(at 224.79 17.78 0)
			(effects
				(font
					(size 1.27 1.27)
					(thickness 0.15)
				)
				(justify left bottom)
				(hide yes)
			)
		)
		(property "Datasheet" "https://www.murata.com/products/productdetail?partno=GRM155R61H104KE14%23"
			(at 222.25 17.78 0)
			(effects
				(font
					(size 1.27 1.27)
					(thickness 0.15)
				)
				(justify left bottom)
				(hide yes)
			)
		)
		(property "Description" "SMD Multilayer Ceramic Capacitor, 0.1 µF, 50 V, 0402 [1005 Metric], ± 10%, X5R, GRM Series"
			(at 204.47 17.78 0)
			(effects
				(font
					(size 1.27 1.27)
				)
				(justify left bottom)
				(hide yes)
			)
		)
		(property "MPN" "GRM155R61H104KE14D"
			(at 219.71 17.78 0)
			(effects
				(font
					(size 1.27 1.27)
					(thickness 0.15)
				)
				(justify left bottom)
				(hide yes)
			)
		)
		(property "Manufacturer" "Murata"
			(at 217.17 17.78 0)
			(effects
				(font
					(size 1.27 1.27)
					(thickness 0.15)
				)
				(justify left bottom)
				(hide yes)
			)
		)
		(property "License" "Apache-2.0"
			(at 214.63 17.78 0)
			(effects
				(font
					(size 1.27 1.27)
					(thickness 0.15)
				)
				(justify left bottom)
				(hide yes)
			)
		)
		(property "Author" "Antmicro"
			(at 212.09 17.78 0)
			(effects
				(font
					(size 1.27 1.27)
					(thickness 0.15)
				)
				(justify left bottom)
				(hide yes)
			)
		)
		(property "Val" "100n"
			(at 235.712 36.83 90)
			(effects
				(font
					(size 1.27 1.27)
					(thickness 0.15)
				)
				(justify right)
			)
		)
		(property "Voltage" "50V"
			(at 209.55 17.78 0)
			(effects
				(font
					(size 1.27 1.27)
				)
				(justify left bottom)
				(hide yes)
			)
		)
		(property "Dielectric" "X5R"
			(at 207.01 17.78 0)
			(effects
				(font
					(size 1.27 1.27)
				)
				(justify left bottom)
				(hide yes)
			)
		)
		(pin "1"
		)
		(pin "2"
		)
		(instances
			(project "OCuLink to 10GbE adapter"
				(path ""
					(reference "C5")
					(unit 1)
				)
			)
		)
	)
	(symbol
		(lib_id "antmicropower:GND")
		(at 279.4 246.38 0)
		(mirror y)
		(unit 1)
		(exclude_from_sim no)
		(in_bom yes)
		(on_board yes)
		(dnp no)
		(property "Reference" "#PWR0363"
			(at 270.51 248.92 0)
			(effects
				(font
					(size 1.27 1.27)
					(thickness 0.15)
				)
				(justify left bottom)
				(hide yes)
			)
		)
		(property "Value" "GND"
			(at 279.4 250.19 0)
			(effects
				(font
					(size 1.27 1.27)
					(thickness 0.15)
				)
			)
		)
		(property "Footprint" ""
			(at 270.51 254 0)
			(effects
				(font
					(size 1.27 1.27)
					(thickness 0.15)
				)
				(justify left bottom)
				(hide yes)
			)
		)
		(property "Datasheet" ""
			(at 270.51 259.08 0)
			(effects
				(font
					(size 1.27 1.27)
					(thickness 0.15)
				)
				(justify left bottom)
				(hide yes)
			)
		)
		(property "Description" ""
			(at 279.4 246.38 0)
			(effects
				(font
					(size 1.27 1.27)
				)
				(hide yes)
			)
		)
		(property "Author" "Antmicro"
			(at 270.51 254 0)
			(effects
				(font
					(size 1.27 1.27)
					(thickness 0.15)
				)
				(justify left bottom)
				(hide yes)
			)
		)
		(property "License" "Apache-2.0"
			(at 270.51 256.54 0)
			(effects
				(font
					(size 1.27 1.27)
					(thickness 0.15)
				)
				(justify left bottom)
				(hide yes)
			)
		)
		(pin "1"
		)
		(instances
			(project "oculink-to-10gbe-adapter"
				(path ""
					(reference "#PWR0363")
					(unit 1)
				)
			)
		)
	)
	(symbol
		(lib_id "antmicropower:GND")
		(at 332.74 195.58 0)
		(unit 1)
		(exclude_from_sim no)
		(in_bom yes)
		(on_board yes)
		(dnp no)
		(property "Reference" "#PWR058"
			(at 341.63 198.12 0)
			(effects
				(font
					(size 1.27 1.27)
					(thickness 0.15)
				)
				(justify left bottom)
				(hide yes)
			)
		)
		(property "Value" "GND"
			(at 332.74 199.39 0)
			(effects
				(font
					(size 1.27 1.27)
					(thickness 0.15)
				)
			)
		)
		(property "Footprint" ""
			(at 341.63 203.2 0)
			(effects
				(font
					(size 1.27 1.27)
					(thickness 0.15)
				)
				(justify left bottom)
				(hide yes)
			)
		)
		(property "Datasheet" ""
			(at 341.63 208.28 0)
			(effects
				(font
					(size 1.27 1.27)
					(thickness 0.15)
				)
				(justify left bottom)
				(hide yes)
			)
		)
		(property "Description" ""
			(at 332.74 195.58 0)
			(effects
				(font
					(size 1.27 1.27)
				)
				(hide yes)
			)
		)
		(property "Author" "Antmicro"
			(at 341.63 203.2 0)
			(effects
				(font
					(size 1.27 1.27)
					(thickness 0.15)
				)
				(justify left bottom)
				(hide yes)
			)
		)
		(property "License" "Apache-2.0"
			(at 341.63 205.74 0)
			(effects
				(font
					(size 1.27 1.27)
					(thickness 0.15)
				)
				(justify left bottom)
				(hide yes)
			)
		)
		(pin "1"
		)
		(instances
			(project "OCuLink to 10GbE adapter"
				(path ""
					(reference "#PWR058")
					(unit 1)
				)
			)
		)
	)
	(symbol
		(lib_id "antmicropower:GND")
		(at 297.18 195.58 0)
		(unit 1)
		(exclude_from_sim no)
		(in_bom yes)
		(on_board yes)
		(dnp no)
		(property "Reference" "#PWR057"
			(at 306.07 198.12 0)
			(effects
				(font
					(size 1.27 1.27)
					(thickness 0.15)
				)
				(justify left bottom)
				(hide yes)
			)
		)
		(property "Value" "GND"
			(at 297.18 199.39 0)
			(effects
				(font
					(size 1.27 1.27)
					(thickness 0.15)
				)
			)
		)
		(property "Footprint" ""
			(at 306.07 203.2 0)
			(effects
				(font
					(size 1.27 1.27)
					(thickness 0.15)
				)
				(justify left bottom)
				(hide yes)
			)
		)
		(property "Datasheet" ""
			(at 306.07 208.28 0)
			(effects
				(font
					(size 1.27 1.27)
					(thickness 0.15)
				)
				(justify left bottom)
				(hide yes)
			)
		)
		(property "Description" ""
			(at 297.18 195.58 0)
			(effects
				(font
					(size 1.27 1.27)
				)
				(hide yes)
			)
		)
		(property "Author" "Antmicro"
			(at 306.07 203.2 0)
			(effects
				(font
					(size 1.27 1.27)
					(thickness 0.15)
				)
				(justify left bottom)
				(hide yes)
			)
		)
		(property "License" "Apache-2.0"
			(at 306.07 205.74 0)
			(effects
				(font
					(size 1.27 1.27)
					(thickness 0.15)
				)
				(justify left bottom)
				(hide yes)
			)
		)
		(pin "1"
		)
		(instances
			(project "OCuLink to 10GbE adapter"
				(path ""
					(reference "#PWR057")
					(unit 1)
				)
			)
		)
	)
	(symbol
		(lib_id "antmicroResistors0402:R_16k_0402")
		(at 332.74 71.12 90)
		(unit 1)
		(exclude_from_sim no)
		(in_bom yes)
		(on_board yes)
		(dnp no)
		(property "Reference" "R9"
			(at 334.01 67.31 90)
			(effects
				(font
					(size 1.27 1.27)
					(thickness 0.15)
				)
				(justify right)
			)
		)
		(property "Value" "R_16k_0402"
			(at 345.44 50.8 0)
			(effects
				(font
					(size 1.27 1.27)
					(thickness 0.15)
				)
				(justify left bottom)
				(hide yes)
			)
		)
		(property "Footprint" "antmicro-footprints:R_0402_1005Metric"
			(at 347.98 50.8 0)
			(effects
				(font
					(size 1.27 1.27)
					(thickness 0.15)
				)
				(justify left bottom)
				(hide yes)
			)
		)
		(property "Datasheet" "https://www.bourns.com/docs/product-datasheets/cr.pdf"
			(at 350.52 50.8 0)
			(effects
				(font
					(size 1.27 1.27)
					(thickness 0.15)
				)
				(justify left bottom)
				(hide yes)
			)
		)
		(property "Description" "SMD Chip Resistor"
			(at 363.22 50.8 0)
			(effects
				(font
					(size 1.27 1.27)
				)
				(justify left bottom)
				(hide yes)
			)
		)
		(property "MPN" "CR0402-FX-1602GLF"
			(at 353.06 50.8 0)
			(effects
				(font
					(size 1.27 1.27)
					(thickness 0.15)
				)
				(justify left bottom)
				(hide yes)
			)
		)
		(property "Manufacturer" "Bourns"
			(at 355.6 50.8 0)
			(effects
				(font
					(size 1.27 1.27)
					(thickness 0.15)
				)
				(justify left bottom)
				(hide yes)
			)
		)
		(property "License" "Apache-2.0"
			(at 358.14 50.8 0)
			(effects
				(font
					(size 1.27 1.27)
					(thickness 0.15)
				)
				(justify left bottom)
				(hide yes)
			)
		)
		(property "Author" "Antmicro"
			(at 360.68 50.8 0)
			(effects
				(font
					(size 1.27 1.27)
					(thickness 0.15)
				)
				(justify left bottom)
				(hide yes)
			)
		)
		(property "Val" "16k"
			(at 334.01 69.85 90)
			(effects
				(font
					(size 1.27 1.27)
					(thickness 0.15)
				)
				(justify right)
			)
		)
		(property "Tolerance" "1%"
			(at 342.9 50.8 0)
			(effects
				(font
					(size 1.27 1.27)
				)
				(justify left bottom)
				(hide yes)
			)
		)
		(pin "2"
		)
		(pin "1"
		)
		(instances
			(project ""
				(path ""
					(reference "R9")
					(unit 1)
				)
			)
		)
	)
	(symbol
		(lib_id "antmicropower:PWR_FLAG")
		(at 74.93 82.55 0)
		(unit 1)
		(exclude_from_sim no)
		(in_bom yes)
		(on_board yes)
		(dnp no)
		(property "Reference" "#FLG03"
			(at 74.93 80.645 0)
			(effects
				(font
					(size 1.27 1.27)
				)
				(hide yes)
			)
		)
		(property "Value" "PWR_FLAG"
			(at 74.93 78.74 0)
			(effects
				(font
					(size 1.27 1.27)
				)
			)
		)
		(property "Footprint" ""
			(at 74.93 82.55 0)
			(effects
				(font
					(size 1.27 1.27)
				)
				(hide yes)
			)
		)
		(property "Datasheet" ""
			(at 74.93 82.55 0)
			(effects
				(font
					(size 1.27 1.27)
				)
				(hide yes)
			)
		)
		(property "Description" ""
			(at 74.93 82.55 0)
			(effects
				(font
					(size 1.27 1.27)
				)
				(hide yes)
			)
		)
		(pin "1"
		)
		(instances
			(project "OCuLink to 10GbE adapter"
				(path ""
					(reference "#FLG03")
					(unit 1)
				)
			)
		)
	)
	(symbol
		(lib_id "antmicroDCDCConverters:TPS566231P")
		(at 276.86 177.8 0)
		(unit 1)
		(exclude_from_sim no)
		(in_bom yes)
		(on_board yes)
		(dnp no)
		(fields_autoplaced yes)
		(property "Reference" "U5"
			(at 285.75 171.45 0)
			(effects
				(font
					(size 1.27 1.27)
					(thickness 0.15)
				)
			)
		)
		(property "Value" "TPS566231P"
			(at 309.88 182.88 0)
			(effects
				(font
					(size 1.27 1.27)
					(thickness 0.15)
				)
				(justify left bottom)
				(hide yes)
			)
		)
		(property "Footprint" "antmicro-footprints:VQFN-HR-9_2x1.5mm"
			(at 309.88 185.42 0)
			(effects
				(font
					(size 1.27 1.27)
					(thickness 0.15)
				)
				(justify left bottom)
				(hide yes)
			)
		)
		(property "Datasheet" "https://www.ti.com/lit/ds/symlink/tps566231.pdf"
			(at 309.88 187.96 0)
			(effects
				(font
					(size 1.27 1.27)
					(thickness 0.15)
				)
				(justify left bottom)
				(hide yes)
			)
		)
		(property "Description" "Switching Voltage Regulators 3-V to 18-V, 6-A synchronous buck converter"
			(at 309.88 200.66 0)
			(effects
				(font
					(size 1.27 1.27)
				)
				(justify left bottom)
				(hide yes)
			)
		)
		(property "Manufacturer" "Texas Instruments"
			(at 309.88 190.5 0)
			(effects
				(font
					(size 1.27 1.27)
					(thickness 0.15)
				)
				(justify left bottom)
				(hide yes)
			)
		)
		(property "MPN" "TPS566231PRQFR"
			(at 285.75 173.99 0)
			(effects
				(font
					(size 1.27 1.27)
					(thickness 0.15)
				)
			)
		)
		(property "Author" "Antmicro"
			(at 309.88 195.58 0)
			(effects
				(font
					(size 1.27 1.27)
					(thickness 0.15)
				)
				(justify left bottom)
				(hide yes)
			)
		)
		(property "License" "Apache-2.0"
			(at 309.88 198.12 0)
			(effects
				(font
					(size 1.27 1.27)
					(thickness 0.15)
				)
				(justify left bottom)
				(hide yes)
			)
		)
		(pin "1"
		)
		(pin "2"
		)
		(pin "3"
		)
		(pin "9"
		)
		(pin "5"
		)
		(pin "6"
		)
		(pin "8"
		)
		(pin "4"
		)
		(pin "7"
		)
		(instances
			(project "OCuLink to 10GbE adapter"
				(path ""
					(reference "U5")
					(unit 1)
				)
			)
		)
	)
	(symbol
		(lib_id "antmicropower:GND")
		(at 58.42 102.87 0)
		(unit 1)
		(exclude_from_sim no)
		(in_bom yes)
		(on_board yes)
		(dnp no)
		(property "Reference" "#PWR025"
			(at 67.31 105.41 0)
			(effects
				(font
					(size 1.27 1.27)
					(thickness 0.15)
				)
				(justify left bottom)
				(hide yes)
			)
		)
		(property "Value" "GND"
			(at 58.42 106.68 0)
			(effects
				(font
					(size 1.27 1.27)
					(thickness 0.15)
				)
			)
		)
		(property "Footprint" ""
			(at 67.31 110.49 0)
			(effects
				(font
					(size 1.27 1.27)
					(thickness 0.15)
				)
				(justify left bottom)
				(hide yes)
			)
		)
		(property "Datasheet" ""
			(at 67.31 115.57 0)
			(effects
				(font
					(size 1.27 1.27)
					(thickness 0.15)
				)
				(justify left bottom)
				(hide yes)
			)
		)
		(property "Description" ""
			(at 58.42 102.87 0)
			(effects
				(font
					(size 1.27 1.27)
				)
				(hide yes)
			)
		)
		(property "Author" "Antmicro"
			(at 67.31 110.49 0)
			(effects
				(font
					(size 1.27 1.27)
					(thickness 0.15)
				)
				(justify left bottom)
				(hide yes)
			)
		)
		(property "License" "Apache-2.0"
			(at 67.31 113.03 0)
			(effects
				(font
					(size 1.27 1.27)
					(thickness 0.15)
				)
				(justify left bottom)
				(hide yes)
			)
		)
		(pin "1"
		)
		(instances
			(project "OCuLink to 10GbE adapter"
				(path ""
					(reference "#PWR025")
					(unit 1)
				)
			)
		)
	)
	(symbol
		(lib_id "antmicroResistors0402:R_100k_0402")
		(at 196.85 41.91 270)
		(mirror x)
		(unit 1)
		(exclude_from_sim no)
		(in_bom yes)
		(on_board yes)
		(dnp no)
		(property "Reference" "R5"
			(at 195.58 38.1 90)
			(effects
				(font
					(size 1.27 1.27)
					(thickness 0.15)
				)
				(justify right)
			)
		)
		(property "Value" "R_100k_0402"
			(at 184.15 21.59 0)
			(effects
				(font
					(size 1.27 1.27)
					(thickness 0.15)
				)
				(justify left bottom)
				(hide yes)
			)
		)
		(property "Footprint" "antmicro-footprints:R_0402_1005Metric"
			(at 181.61 21.59 0)
			(effects
				(font
					(size 1.27 1.27)
					(thickness 0.15)
				)
				(justify left bottom)
				(hide yes)
			)
		)
		(property "Datasheet" "https://www.bourns.com/docs/product-datasheets/cr.pdf"
			(at 179.07 21.59 0)
			(effects
				(font
					(size 1.27 1.27)
					(thickness 0.15)
				)
				(justify left bottom)
				(hide yes)
			)
		)
		(property "Description" "SMD Chip Resistor, 100 kohm, ± 1%, 62.5 mW, 0402 [1005 Metric], Thick Film, General Purpose"
			(at 166.37 21.59 0)
			(effects
				(font
					(size 1.27 1.27)
				)
				(justify left bottom)
				(hide yes)
			)
		)
		(property "MPN" "CR0402-FX-1003GLF"
			(at 176.53 21.59 0)
			(effects
				(font
					(size 1.27 1.27)
					(thickness 0.15)
				)
				(justify left bottom)
				(hide yes)
			)
		)
		(property "Manufacturer" "Bourns"
			(at 173.99 21.59 0)
			(effects
				(font
					(size 1.27 1.27)
					(thickness 0.15)
				)
				(justify left bottom)
				(hide yes)
			)
		)
		(property "License" "Apache-2.0"
			(at 171.45 21.59 0)
			(effects
				(font
					(size 1.27 1.27)
					(thickness 0.15)
				)
				(justify left bottom)
				(hide yes)
			)
		)
		(property "Author" "Antmicro"
			(at 168.91 21.59 0)
			(effects
				(font
					(size 1.27 1.27)
					(thickness 0.15)
				)
				(justify left bottom)
				(hide yes)
			)
		)
		(property "Val" "100k"
			(at 195.58 40.64 90)
			(effects
				(font
					(size 1.27 1.27)
					(thickness 0.15)
				)
				(justify right)
			)
		)
		(property "Tolerance" "1%"
			(at 186.69 21.59 0)
			(effects
				(font
					(size 1.27 1.27)
				)
				(justify left bottom)
				(hide yes)
			)
		)
		(pin "1"
		)
		(pin "2"
		)
		(instances
			(project "OCuLink to 10GbE adapter"
				(path ""
					(reference "R5")
					(unit 1)
				)
			)
		)
	)
	(symbol
		(lib_id "antmicroTVSDiodes:SZSMF4L14AT3G")
		(at 58.42 91.44 270)
		(unit 1)
		(exclude_from_sim no)
		(in_bom yes)
		(on_board yes)
		(dnp no)
		(fields_autoplaced yes)
		(property "Reference" "D1"
			(at 60.96 92.71 90)
			(effects
				(font
					(size 1.27 1.27)
					(thickness 0.15)
				)
				(justify left)
			)
		)
		(property "Value" "SZSMF4L14AT3G"
			(at 48.26 106.68 0)
			(effects
				(font
					(size 1.27 1.27)
					(thickness 0.15)
				)
				(justify left bottom)
				(hide yes)
			)
		)
		(property "Footprint" "antmicro-footprints:SOD-123FL"
			(at 45.72 106.68 0)
			(effects
				(font
					(size 1.27 1.27)
					(thickness 0.15)
				)
				(justify left bottom)
				(hide yes)
			)
		)
		(property "Datasheet" "https://www.mouser.com/datasheet/2/240/media-3320461.pdf"
			(at 43.18 106.68 0)
			(effects
				(font
					(size 1.27 1.27)
					(thickness 0.15)
				)
				(justify left bottom)
				(hide yes)
			)
		)
		(property "Description" "ESD, TVS Diode, 14V, UNI, 400W, SOD-123FL"
			(at 58.42 91.44 0)
			(effects
				(font
					(size 1.27 1.27)
				)
				(hide yes)
			)
		)
		(property "MPN" "SZSMF4L12AT3G"
			(at 60.96 95.25 90)
			(effects
				(font
					(size 1.27 1.27)
					(thickness 0.15)
				)
				(justify left)
			)
		)
		(property "Author" "Antmicro"
			(at 40.64 106.68 0)
			(effects
				(font
					(size 1.27 1.27)
					(thickness 0.15)
				)
				(justify left bottom)
				(hide yes)
			)
		)
		(property "License" "Apache-2.0"
			(at 38.1 106.68 0)
			(effects
				(font
					(size 1.27 1.27)
					(thickness 0.15)
				)
				(justify left bottom)
				(hide yes)
			)
		)
		(property "Manufacturer" "Littelfuse"
			(at 35.56 106.68 0)
			(effects
				(font
					(size 1.27 1.27)
					(thickness 0.15)
				)
				(justify left bottom)
				(hide yes)
			)
		)
		(pin "1"
		)
		(pin "2"
		)
		(instances
			(project ""
				(path ""
					(reference "D1")
					(unit 1)
				)
			)
		)
	)
	(symbol
		(lib_id "antmicropower:GND")
		(at 217.17 157.48 0)
		(unit 1)
		(exclude_from_sim no)
		(in_bom yes)
		(on_board yes)
		(dnp no)
		(property "Reference" "#PWR037"
			(at 226.06 160.02 0)
			(effects
				(font
					(size 1.27 1.27)
					(thickness 0.15)
				)
				(justify left bottom)
				(hide yes)
			)
		)
		(property "Value" "GND"
			(at 217.17 161.29 0)
			(effects
				(font
					(size 1.27 1.27)
					(thickness 0.15)
				)
			)
		)
		(property "Footprint" ""
			(at 226.06 165.1 0)
			(effects
				(font
					(size 1.27 1.27)
					(thickness 0.15)
				)
				(justify left bottom)
				(hide yes)
			)
		)
		(property "Datasheet" ""
			(at 226.06 170.18 0)
			(effects
				(font
					(size 1.27 1.27)
					(thickness 0.15)
				)
				(justify left bottom)
				(hide yes)
			)
		)
		(property "Description" ""
			(at 217.17 157.48 0)
			(effects
				(font
					(size 1.27 1.27)
				)
				(hide yes)
			)
		)
		(property "Author" "Antmicro"
			(at 226.06 165.1 0)
			(effects
				(font
					(size 1.27 1.27)
					(thickness 0.15)
				)
				(justify left bottom)
				(hide yes)
			)
		)
		(property "License" "Apache-2.0"
			(at 226.06 167.64 0)
			(effects
				(font
					(size 1.27 1.27)
					(thickness 0.15)
				)
				(justify left bottom)
				(hide yes)
			)
		)
		(pin "1"
		)
		(instances
			(project "OCuLink to 10GbE adapter"
				(path ""
					(reference "#PWR037")
					(unit 1)
				)
			)
		)
	)
	(symbol
		(lib_id "antmicroResistors0402:R_1k_0402")
		(at 279.4 231.14 90)
		(unit 1)
		(exclude_from_sim no)
		(in_bom yes)
		(on_board yes)
		(dnp no)
		(property "Reference" "R148"
			(at 280.67 227.33 90)
			(effects
				(font
					(size 1.27 1.27)
					(thickness 0.15)
				)
				(justify right)
			)
		)
		(property "Value" "R_1k_0402"
			(at 292.1 210.82 0)
			(effects
				(font
					(size 1.27 1.27)
					(thickness 0.15)
				)
				(justify left bottom)
				(hide yes)
			)
		)
		(property "Footprint" "antmicro-footprints:R_0402_1005Metric"
			(at 294.64 210.82 0)
			(effects
				(font
					(size 1.27 1.27)
					(thickness 0.15)
				)
				(justify left bottom)
				(hide yes)
			)
		)
		(property "Datasheet" "https://www.bourns.com/docs/product-datasheets/cr.pdf"
			(at 297.18 210.82 0)
			(effects
				(font
					(size 1.27 1.27)
					(thickness 0.15)
				)
				(justify left bottom)
				(hide yes)
			)
		)
		(property "Description" "SMD Chip Resistor, 1 kohm, ± 1%, 63 mW, 0402 [1005 Metric], Thick Film, General Purpose"
			(at 309.88 210.82 0)
			(effects
				(font
					(size 1.27 1.27)
				)
				(justify left bottom)
				(hide yes)
			)
		)
		(property "MPN" "CR0402-FX-1001GLF"
			(at 299.72 210.82 0)
			(effects
				(font
					(size 1.27 1.27)
					(thickness 0.15)
				)
				(justify left bottom)
				(hide yes)
			)
		)
		(property "Manufacturer" "Bourns"
			(at 302.26 210.82 0)
			(effects
				(font
					(size 1.27 1.27)
					(thickness 0.15)
				)
				(justify left bottom)
				(hide yes)
			)
		)
		(property "License" "Apache-2.0"
			(at 304.8 210.82 0)
			(effects
				(font
					(size 1.27 1.27)
					(thickness 0.15)
				)
				(justify left bottom)
				(hide yes)
			)
		)
		(property "Author" "Antmicro"
			(at 307.34 210.82 0)
			(effects
				(font
					(size 1.27 1.27)
					(thickness 0.15)
				)
				(justify left bottom)
				(hide yes)
			)
		)
		(property "Val" "1k"
			(at 280.67 229.87 90)
			(effects
				(font
					(size 1.27 1.27)
					(thickness 0.15)
				)
				(justify right)
			)
		)
		(property "Tolerance" "1%"
			(at 289.56 210.82 0)
			(effects
				(font
					(size 1.27 1.27)
				)
				(justify left bottom)
				(hide yes)
			)
		)
		(pin "1"
		)
		(pin "2"
		)
		(instances
			(project "oculink-to-10gbe-adapter"
				(path ""
					(reference "R148")
					(unit 1)
				)
			)
		)
	)
	(symbol
		(lib_id "antmicroCapacitors0603:C_22u_16V_0603")
		(at 227.33 152.4 270)
		(mirror x)
		(unit 1)
		(exclude_from_sim no)
		(in_bom yes)
		(on_board yes)
		(dnp no)
		(property "Reference" "C31"
			(at 225.552 148.59 90)
			(effects
				(font
					(size 1.27 1.27)
					(thickness 0.15)
				)
				(justify right)
			)
		)
		(property "Value" "C_22u_16V_0603"
			(at 217.17 132.08 0)
			(effects
				(font
					(size 1.27 1.27)
					(thickness 0.15)
				)
				(justify left bottom)
				(hide yes)
			)
		)
		(property "Footprint" "antmicro-footprints:C_0603_1608Metric_EIA"
			(at 214.63 132.08 0)
			(effects
				(font
					(size 1.27 1.27)
					(thickness 0.15)
				)
				(justify left bottom)
				(hide yes)
			)
		)
		(property "Datasheet" "https://product.samsungsem.com/mlcc/CL10A226MO7JZN.do"
			(at 212.09 132.08 0)
			(effects
				(font
					(size 1.27 1.27)
					(thickness 0.15)
				)
				(justify left bottom)
				(hide yes)
			)
		)
		(property "Description" "SMD Multilayer Ceramic Capacitor"
			(at 227.33 152.4 0)
			(effects
				(font
					(size 1.27 1.27)
				)
				(hide yes)
			)
		)
		(property "MPN" "CL10A226MO7JZNC"
			(at 209.55 132.08 0)
			(effects
				(font
					(size 1.27 1.27)
					(thickness 0.15)
				)
				(justify left bottom)
				(hide yes)
			)
		)
		(property "Manufacturer" "Samsung Electro-Mechanics"
			(at 207.01 132.08 0)
			(effects
				(font
					(size 1.27 1.27)
					(thickness 0.15)
				)
				(justify left bottom)
				(hide yes)
			)
		)
		(property "License" "Apache-2.0"
			(at 204.47 132.08 0)
			(effects
				(font
					(size 1.27 1.27)
					(thickness 0.15)
				)
				(justify left bottom)
				(hide yes)
			)
		)
		(property "Author" "Antmicro"
			(at 201.93 132.08 0)
			(effects
				(font
					(size 1.27 1.27)
					(thickness 0.15)
				)
				(justify left bottom)
				(hide yes)
			)
		)
		(property "Val" "22u"
			(at 225.552 151.13 90)
			(effects
				(font
					(size 1.27 1.27)
					(thickness 0.15)
				)
				(justify right)
			)
		)
		(property "Voltage" "16V"
			(at 224.79 152.3935 90)
			(effects
				(font
					(size 1.27 1.27)
				)
				(justify right)
				(hide yes)
			)
		)
		(property "Dielectric" ""
			(at 196.85 132.08 0)
			(effects
				(font
					(size 1.27 1.27)
				)
				(justify left bottom)
				(hide yes)
			)
		)
		(property "Public" "False"
			(at 194.31 132.08 0)
			(effects
				(font
					(size 1.27 1.27)
				)
				(justify left bottom)
				(hide yes)
			)
		)
		(pin "2"
		)
		(pin "1"
		)
		(instances
			(project "OCuLink to 10GbE adapter"
				(path ""
					(reference "C31")
					(unit 1)
				)
			)
		)
	)
	(symbol
		(lib_id "antmicropower:GND")
		(at 227.33 195.58 0)
		(unit 1)
		(exclude_from_sim no)
		(in_bom yes)
		(on_board yes)
		(dnp no)
		(property "Reference" "#PWR054"
			(at 236.22 198.12 0)
			(effects
				(font
					(size 1.27 1.27)
					(thickness 0.15)
				)
				(justify left bottom)
				(hide yes)
			)
		)
		(property "Value" "GND"
			(at 227.33 199.39 0)
			(effects
				(font
					(size 1.27 1.27)
					(thickness 0.15)
				)
			)
		)
		(property "Footprint" ""
			(at 236.22 203.2 0)
			(effects
				(font
					(size 1.27 1.27)
					(thickness 0.15)
				)
				(justify left bottom)
				(hide yes)
			)
		)
		(property "Datasheet" ""
			(at 236.22 208.28 0)
			(effects
				(font
					(size 1.27 1.27)
					(thickness 0.15)
				)
				(justify left bottom)
				(hide yes)
			)
		)
		(property "Description" ""
			(at 227.33 195.58 0)
			(effects
				(font
					(size 1.27 1.27)
				)
				(hide yes)
			)
		)
		(property "Author" "Antmicro"
			(at 236.22 203.2 0)
			(effects
				(font
					(size 1.27 1.27)
					(thickness 0.15)
				)
				(justify left bottom)
				(hide yes)
			)
		)
		(property "License" "Apache-2.0"
			(at 236.22 205.74 0)
			(effects
				(font
					(size 1.27 1.27)
					(thickness 0.15)
				)
				(justify left bottom)
				(hide yes)
			)
		)
		(pin "1"
		)
		(instances
			(project "OCuLink to 10GbE adapter"
				(path ""
					(reference "#PWR054")
					(unit 1)
				)
			)
		)
	)
	(symbol
		(lib_id "antmicropower:GND")
		(at 53.34 172.72 0)
		(unit 1)
		(exclude_from_sim no)
		(in_bom yes)
		(on_board yes)
		(dnp no)
		(property "Reference" "#PWR046"
			(at 62.23 175.26 0)
			(effects
				(font
					(size 1.27 1.27)
					(thickness 0.15)
				)
				(justify left bottom)
				(hide yes)
			)
		)
		(property "Value" "GND"
			(at 53.34 176.53 0)
			(effects
				(font
					(size 1.27 1.27)
					(thickness 0.15)
				)
			)
		)
		(property "Footprint" ""
			(at 62.23 180.34 0)
			(effects
				(font
					(size 1.27 1.27)
					(thickness 0.15)
				)
				(justify left bottom)
				(hide yes)
			)
		)
		(property "Datasheet" ""
			(at 62.23 185.42 0)
			(effects
				(font
					(size 1.27 1.27)
					(thickness 0.15)
				)
				(justify left bottom)
				(hide yes)
			)
		)
		(property "Description" ""
			(at 53.34 172.72 0)
			(effects
				(font
					(size 1.27 1.27)
				)
				(hide yes)
			)
		)
		(property "Author" "Antmicro"
			(at 62.23 180.34 0)
			(effects
				(font
					(size 1.27 1.27)
					(thickness 0.15)
				)
				(justify left bottom)
				(hide yes)
			)
		)
		(property "License" "Apache-2.0"
			(at 62.23 182.88 0)
			(effects
				(font
					(size 1.27 1.27)
					(thickness 0.15)
				)
				(justify left bottom)
				(hide yes)
			)
		)
		(pin "1"
		)
		(instances
			(project "OCuLink to 10GbE adapter"
				(path ""
					(reference "#PWR046")
					(unit 1)
				)
			)
		)
	)
	(symbol
		(lib_id "antmicroCapacitors0402:C_33p_0402")
		(at 327.66 71.12 270)
		(mirror x)
		(unit 1)
		(exclude_from_sim no)
		(in_bom no)
		(on_board yes)
		(dnp yes)
		(property "Reference" "C11"
			(at 325.882 67.31 90)
			(effects
				(font
					(size 1.27 1.27)
					(thickness 0.15)
				)
				(justify right)
			)
		)
		(property "Value" "C_33p_0402"
			(at 317.5 50.8 0)
			(effects
				(font
					(size 1.27 1.27)
					(thickness 0.15)
				)
				(justify left bottom)
				(hide yes)
			)
		)
		(property "Footprint" "antmicro-footprints:C_0402_1005Metric"
			(at 314.96 50.8 0)
			(effects
				(font
					(size 1.27 1.27)
					(thickness 0.15)
				)
				(justify left bottom)
				(hide yes)
			)
		)
		(property "Datasheet" "https://spicat.kyocera-avx.com/product/mlcc/chartview/04025A330FAT2A/"
			(at 312.42 50.8 0)
			(effects
				(font
					(size 1.27 1.27)
					(thickness 0.15)
				)
				(justify left bottom)
				(hide yes)
			)
		)
		(property "Description" "SMD Multilayer Ceramic Capacitor, 33 pF, 50 V, 0402 [1005 Metric], ± 5%, C0G / NP0, MC"
			(at 294.64 50.8 0)
			(effects
				(font
					(size 1.27 1.27)
				)
				(justify left bottom)
				(hide yes)
			)
		)
		(property "MPN" "04025A330FAT2A"
			(at 309.88 50.8 0)
			(effects
				(font
					(size 1.27 1.27)
					(thickness 0.15)
				)
				(justify left bottom)
				(hide yes)
			)
		)
		(property "Manufacturer" "KYOCERA AVX"
			(at 307.34 50.8 0)
			(effects
				(font
					(size 1.27 1.27)
					(thickness 0.15)
				)
				(justify left bottom)
				(hide yes)
			)
		)
		(property "License" "Apache-2.0"
			(at 304.8 50.8 0)
			(effects
				(font
					(size 1.27 1.27)
					(thickness 0.15)
				)
				(justify left bottom)
				(hide yes)
			)
		)
		(property "Author" "Antmicro"
			(at 302.26 50.8 0)
			(effects
				(font
					(size 1.27 1.27)
					(thickness 0.15)
				)
				(justify left bottom)
				(hide yes)
			)
		)
		(property "Val" "33p"
			(at 325.882 69.85 90)
			(effects
				(font
					(size 1.27 1.27)
					(thickness 0.15)
				)
				(justify right)
			)
		)
		(property "Voltage" ""
			(at 299.72 50.8 0)
			(effects
				(font
					(size 1.27 1.27)
				)
				(justify left bottom)
				(hide yes)
			)
		)
		(property "Dielectric" ""
			(at 297.18 50.8 0)
			(effects
				(font
					(size 1.27 1.27)
				)
				(justify left bottom)
				(hide yes)
			)
		)
		(pin "2"
		)
		(pin "1"
		)
		(instances
			(project "OCuLink to 10GbE adapter"
				(path ""
					(reference "C11")
					(unit 1)
				)
			)
		)
	)
	(symbol
		(lib_id "antmicroResistors0402:R_20k_0402")
		(at 332.74 41.91 90)
		(unit 1)
		(exclude_from_sim no)
		(in_bom yes)
		(on_board yes)
		(dnp no)
		(property "Reference" "R6"
			(at 334.01 38.1 90)
			(effects
				(font
					(size 1.27 1.27)
					(thickness 0.15)
				)
				(justify right)
			)
		)
		(property "Value" "R_20k_0402"
			(at 345.44 21.59 0)
			(effects
				(font
					(size 1.27 1.27)
					(thickness 0.15)
				)
				(justify left bottom)
				(hide yes)
			)
		)
		(property "Footprint" "antmicro-footprints:R_0402_1005Metric"
			(at 347.98 21.59 0)
			(effects
				(font
					(size 1.27 1.27)
					(thickness 0.15)
				)
				(justify left bottom)
				(hide yes)
			)
		)
		(property "Datasheet" "https://www.bourns.com/docs/product-datasheets/cr.pdf"
			(at 350.52 21.59 0)
			(effects
				(font
					(size 1.27 1.27)
					(thickness 0.15)
				)
				(justify left bottom)
				(hide yes)
			)
		)
		(property "Description" "SMD Chip Resistor, 20 kohm, ± 1%, 62.5 mW, 0402 [1005 Metric], Thick Film, General Purpose"
			(at 363.22 21.59 0)
			(effects
				(font
					(size 1.27 1.27)
				)
				(justify left bottom)
				(hide yes)
			)
		)
		(property "MPN" "CR0402-FX-2002GLF"
			(at 353.06 21.59 0)
			(effects
				(font
					(size 1.27 1.27)
					(thickness 0.15)
				)
				(justify left bottom)
				(hide yes)
			)
		)
		(property "Manufacturer" "Bourns"
			(at 355.6 21.59 0)
			(effects
				(font
					(size 1.27 1.27)
					(thickness 0.15)
				)
				(justify left bottom)
				(hide yes)
			)
		)
		(property "License" "Apache-2.0"
			(at 358.14 21.59 0)
			(effects
				(font
					(size 1.27 1.27)
					(thickness 0.15)
				)
				(justify left bottom)
				(hide yes)
			)
		)
		(property "Author" "Antmicro"
			(at 360.68 21.59 0)
			(effects
				(font
					(size 1.27 1.27)
					(thickness 0.15)
				)
				(justify left bottom)
				(hide yes)
			)
		)
		(property "Val" "20k"
			(at 334.01 40.64 90)
			(effects
				(font
					(size 1.27 1.27)
					(thickness 0.15)
				)
				(justify right)
			)
		)
		(property "Tolerance" "1%"
			(at 342.9 21.59 0)
			(effects
				(font
					(size 1.27 1.27)
				)
				(justify left bottom)
				(hide yes)
			)
		)
		(pin "1"
		)
		(pin "2"
		)
		(instances
			(project "oculink-to-10gbe-adapter"
				(path ""
					(reference "R6")
					(unit 1)
				)
			)
		)
	)
	(symbol
		(lib_id "antmicroCapacitors0402:C_100n_0402")
		(at 307.34 182.88 270)
		(mirror x)
		(unit 1)
		(exclude_from_sim no)
		(in_bom yes)
		(on_board yes)
		(dnp no)
		(property "Reference" "C38"
			(at 309.118 179.324 90)
			(effects
				(font
					(size 1.27 1.27)
					(thickness 0.15)
				)
				(justify left)
			)
		)
		(property "Value" "C_100n_0402"
			(at 297.18 162.56 0)
			(effects
				(font
					(size 1.27 1.27)
					(thickness 0.15)
				)
				(justify left bottom)
				(hide yes)
			)
		)
		(property "Footprint" "antmicro-footprints:C_0402_1005Metric"
			(at 294.64 162.56 0)
			(effects
				(font
					(size 1.27 1.27)
					(thickness 0.15)
				)
				(justify left bottom)
				(hide yes)
			)
		)
		(property "Datasheet" "https://www.murata.com/products/productdetail?partno=GRM155R61H104KE14%23"
			(at 292.1 162.56 0)
			(effects
				(font
					(size 1.27 1.27)
					(thickness 0.15)
				)
				(justify left bottom)
				(hide yes)
			)
		)
		(property "Description" "SMD Multilayer Ceramic Capacitor, 0.1 µF, 50 V, 0402 [1005 Metric], ± 10%, X5R, GRM Series"
			(at 274.32 162.56 0)
			(effects
				(font
					(size 1.27 1.27)
				)
				(justify left bottom)
				(hide yes)
			)
		)
		(property "MPN" "GRM155R61H104KE14D"
			(at 289.56 162.56 0)
			(effects
				(font
					(size 1.27 1.27)
					(thickness 0.15)
				)
				(justify left bottom)
				(hide yes)
			)
		)
		(property "Manufacturer" "Murata"
			(at 287.02 162.56 0)
			(effects
				(font
					(size 1.27 1.27)
					(thickness 0.15)
				)
				(justify left bottom)
				(hide yes)
			)
		)
		(property "License" "Apache-2.0"
			(at 284.48 162.56 0)
			(effects
				(font
					(size 1.27 1.27)
					(thickness 0.15)
				)
				(justify left bottom)
				(hide yes)
			)
		)
		(property "Author" "Antmicro"
			(at 281.94 162.56 0)
			(effects
				(font
					(size 1.27 1.27)
					(thickness 0.15)
				)
				(justify left bottom)
				(hide yes)
			)
		)
		(property "Val" "100n"
			(at 309.118 181.864 90)
			(effects
				(font
					(size 1.27 1.27)
					(thickness 0.15)
				)
				(justify left)
			)
		)
		(property "Voltage" "50V"
			(at 279.4 162.56 0)
			(effects
				(font
					(size 1.27 1.27)
				)
				(justify left bottom)
				(hide yes)
			)
		)
		(property "Dielectric" "X5R"
			(at 276.86 162.56 0)
			(effects
				(font
					(size 1.27 1.27)
				)
				(justify left bottom)
				(hide yes)
			)
		)
		(pin "1"
		)
		(pin "2"
		)
		(instances
			(project "OCuLink to 10GbE adapter"
				(path ""
					(reference "C38")
					(unit 1)
				)
			)
		)
	)
	(symbol
		(lib_id "antmicroLEDIndicationDiscrete:LED_G_0603_LG_L29K-G2J1-24-Z")
		(at 91.44 154.94 90)
		(unit 1)
		(exclude_from_sim no)
		(in_bom yes)
		(on_board yes)
		(dnp no)
		(property "Reference" "D3"
			(at 92.71 151.13 90)
			(effects
				(font
					(size 1.27 1.27)
					(thickness 0.15)
				)
				(justify right)
			)
		)
		(property "Value" "LED_G_0603_LG_L29K-G2J1-24-Z"
			(at 99.06 134.62 0)
			(effects
				(font
					(size 1.27 1.27)
					(thickness 0.15)
				)
				(justify left bottom)
				(hide yes)
			)
		)
		(property "Footprint" "antmicro-footprints:LED_0603_1608Metric_G"
			(at 101.6 134.62 0)
			(effects
				(font
					(size 1.27 1.27)
					(thickness 0.15)
				)
				(justify left bottom)
				(hide yes)
			)
		)
		(property "Datasheet" "https://look.ams-osram.com/m/19ee86b3ae0ee95b/original/LG-L29K.pdf"
			(at 104.14 134.62 0)
			(effects
				(font
					(size 1.27 1.27)
					(thickness 0.15)
				)
				(justify left bottom)
				(hide yes)
			)
		)
		(property "Description" "LED, Green, SMD, 0603, 20 mA, 1.7 V, 570 nm"
			(at 91.44 154.94 0)
			(effects
				(font
					(size 1.27 1.27)
				)
				(hide yes)
			)
		)
		(property "MPN" "LG L29K-G2J1-24-Z"
			(at 106.68 134.62 0)
			(effects
				(font
					(size 1.27 1.27)
					(thickness 0.15)
				)
				(justify left bottom)
				(hide yes)
			)
		)
		(property "Manufacturer" "OSRAM"
			(at 109.22 134.62 0)
			(effects
				(font
					(size 1.27 1.27)
					(thickness 0.15)
				)
				(justify left bottom)
				(hide yes)
			)
		)
		(property "Color" "Green"
			(at 92.71 153.6699 90)
			(effects
				(font
					(size 1.27 1.27)
				)
				(justify right)
			)
		)
		(property "Author" "Antmicro"
			(at 111.76 134.62 0)
			(effects
				(font
					(size 1.27 1.27)
					(thickness 0.15)
				)
				(justify left bottom)
				(hide yes)
			)
		)
		(property "License" "Apache-2.0"
			(at 114.3 134.62 0)
			(effects
				(font
					(size 1.27 1.27)
					(thickness 0.15)
				)
				(justify left bottom)
				(hide yes)
			)
		)
		(pin "2"
		)
		(pin "1"
		)
		(instances
			(project "OCuLink to 10GbE adapter"
				(path ""
					(reference "D3")
					(unit 1)
				)
			)
		)
	)
	(symbol
		(lib_id "antmicropower:GND")
		(at 83.82 102.87 0)
		(unit 1)
		(exclude_from_sim no)
		(in_bom yes)
		(on_board yes)
		(dnp no)
		(property "Reference" "#PWR026"
			(at 92.71 105.41 0)
			(effects
				(font
					(size 1.27 1.27)
					(thickness 0.15)
				)
				(justify left bottom)
				(hide yes)
			)
		)
		(property "Value" "GND"
			(at 83.82 106.68 0)
			(effects
				(font
					(size 1.27 1.27)
					(thickness 0.15)
				)
			)
		)
		(property "Footprint" ""
			(at 92.71 110.49 0)
			(effects
				(font
					(size 1.27 1.27)
					(thickness 0.15)
				)
				(justify left bottom)
				(hide yes)
			)
		)
		(property "Datasheet" ""
			(at 92.71 115.57 0)
			(effects
				(font
					(size 1.27 1.27)
					(thickness 0.15)
				)
				(justify left bottom)
				(hide yes)
			)
		)
		(property "Description" ""
			(at 83.82 102.87 0)
			(effects
				(font
					(size 1.27 1.27)
				)
				(hide yes)
			)
		)
		(property "Author" "Antmicro"
			(at 92.71 110.49 0)
			(effects
				(font
					(size 1.27 1.27)
					(thickness 0.15)
				)
				(justify left bottom)
				(hide yes)
			)
		)
		(property "License" "Apache-2.0"
			(at 92.71 113.03 0)
			(effects
				(font
					(size 1.27 1.27)
					(thickness 0.15)
				)
				(justify left bottom)
				(hide yes)
			)
		)
		(pin "1"
		)
		(instances
			(project "OCuLink to 10GbE adapter"
				(path ""
					(reference "#PWR026")
					(unit 1)
				)
			)
		)
	)
	(symbol
		(lib_id "antmicroCapacitors0603:C_22u_16V_0603")
		(at 217.17 76.2 270)
		(mirror x)
		(unit 1)
		(exclude_from_sim no)
		(in_bom yes)
		(on_board yes)
		(dnp no)
		(property "Reference" "C12"
			(at 215.138 72.39 90)
			(effects
				(font
					(size 1.27 1.27)
					(thickness 0.15)
				)
				(justify right)
			)
		)
		(property "Value" "C_22u_16V_0603"
			(at 207.01 55.88 0)
			(effects
				(font
					(size 1.27 1.27)
					(thickness 0.15)
				)
				(justify left bottom)
				(hide yes)
			)
		)
		(property "Footprint" "antmicro-footprints:C_0603_1608Metric_EIA"
			(at 204.47 55.88 0)
			(effects
				(font
					(size 1.27 1.27)
					(thickness 0.15)
				)
				(justify left bottom)
				(hide yes)
			)
		)
		(property "Datasheet" "https://product.samsungsem.com/mlcc/CL10A226MO7JZN.do"
			(at 201.93 55.88 0)
			(effects
				(font
					(size 1.27 1.27)
					(thickness 0.15)
				)
				(justify left bottom)
				(hide yes)
			)
		)
		(property "Description" "SMD Multilayer Ceramic Capacitor"
			(at 217.17 76.2 0)
			(effects
				(font
					(size 1.27 1.27)
				)
				(hide yes)
			)
		)
		(property "MPN" "CL10A226MO7JZNC"
			(at 199.39 55.88 0)
			(effects
				(font
					(size 1.27 1.27)
					(thickness 0.15)
				)
				(justify left bottom)
				(hide yes)
			)
		)
		(property "Manufacturer" "Samsung Electro-Mechanics"
			(at 196.85 55.88 0)
			(effects
				(font
					(size 1.27 1.27)
					(thickness 0.15)
				)
				(justify left bottom)
				(hide yes)
			)
		)
		(property "License" "Apache-2.0"
			(at 194.31 55.88 0)
			(effects
				(font
					(size 1.27 1.27)
					(thickness 0.15)
				)
				(justify left bottom)
				(hide yes)
			)
		)
		(property "Author" "Antmicro"
			(at 191.77 55.88 0)
			(effects
				(font
					(size 1.27 1.27)
					(thickness 0.15)
				)
				(justify left bottom)
				(hide yes)
			)
		)
		(property "Val" "22u"
			(at 215.138 74.93 90)
			(effects
				(font
					(size 1.27 1.27)
					(thickness 0.15)
				)
				(justify right)
			)
		)
		(property "Voltage" "16V"
			(at 214.63 76.1935 90)
			(effects
				(font
					(size 1.27 1.27)
				)
				(justify right)
				(hide yes)
			)
		)
		(property "Dielectric" ""
			(at 186.69 55.88 0)
			(effects
				(font
					(size 1.27 1.27)
				)
				(justify left bottom)
				(hide yes)
			)
		)
		(property "Public" "False"
			(at 184.15 55.88 0)
			(effects
				(font
					(size 1.27 1.27)
				)
				(justify left bottom)
				(hide yes)
			)
		)
		(pin "2"
		)
		(pin "1"
		)
		(instances
			(project "OCuLink to 10GbE adapter"
				(path ""
					(reference "C12")
					(unit 1)
				)
			)
		)
	)
	(symbol
		(lib_id "antmicroTransistorsFETsMOSFETsSingle:2N7002_SOT-23-3")
		(at 312.42 240.03 0)
		(mirror y)
		(unit 1)
		(exclude_from_sim no)
		(in_bom yes)
		(on_board yes)
		(dnp no)
		(property "Reference" "Q4"
			(at 302.26 236.22 0)
			(effects
				(font
					(size 1.27 1.27)
					(thickness 0.15)
				)
				(justify left)
			)
		)
		(property "Value" "2N7002_SOT-23-3"
			(at 289.56 247.65 0)
			(effects
				(font
					(size 1.27 1.27)
					(thickness 0.15)
				)
				(justify left bottom)
				(hide yes)
			)
		)
		(property "Footprint" "antmicro-footprints:SOT-23-3"
			(at 289.56 250.19 0)
			(effects
				(font
					(size 1.27 1.27)
					(thickness 0.15)
				)
				(justify left bottom)
				(hide yes)
			)
		)
		(property "Datasheet" "https://www.onsemi.com/pub/Collateral/NDS7002A-D.PDF"
			(at 289.56 252.73 0)
			(effects
				(font
					(size 1.27 1.27)
					(thickness 0.15)
				)
				(justify left bottom)
				(hide yes)
			)
		)
		(property "Description" "Power MOSFET, N Channel, 60 V, 115 mA, 1.2 ohm, SOT-23, Surface Mount"
			(at 289.56 265.43 0)
			(effects
				(font
					(size 1.27 1.27)
				)
				(justify left bottom)
				(hide yes)
			)
		)
		(property "MPN" "2N7002"
			(at 302.26 238.76 0)
			(effects
				(font
					(size 1.27 1.27)
					(thickness 0.15)
				)
				(justify left)
			)
		)
		(property "Manufacturer" "ON Semiconductor"
			(at 289.56 257.81 0)
			(effects
				(font
					(size 1.27 1.27)
					(thickness 0.15)
				)
				(justify left bottom)
				(hide yes)
			)
		)
		(property "Author" "Antmicro"
			(at 289.56 260.35 0)
			(effects
				(font
					(size 1.27 1.27)
					(thickness 0.15)
				)
				(justify left bottom)
				(hide yes)
			)
		)
		(property "License" "Apache-2.0"
			(at 289.56 262.89 0)
			(effects
				(font
					(size 1.27 1.27)
					(thickness 0.15)
				)
				(justify left bottom)
				(hide yes)
			)
		)
		(pin "3"
		)
		(pin "2"
		)
		(pin "1"
		)
		(instances
			(project "OCuLink to 10GbE adapter"
				(path ""
					(reference "Q4")
					(unit 1)
				)
			)
		)
	)
	(symbol
		(lib_id "antmicroResistors0402:R_0R_0402")
		(at 261.62 73.66 0)
		(unit 1)
		(exclude_from_sim no)
		(in_bom yes)
		(on_board yes)
		(dnp no)
		(property "Reference" "R10"
			(at 264.16 71.374 0)
			(effects
				(font
					(size 1.27 1.27)
					(thickness 0.15)
				)
			)
		)
		(property "Value" "R_0R_0402"
			(at 281.94 86.36 0)
			(effects
				(font
					(size 1.27 1.27)
					(thickness 0.15)
				)
				(justify left bottom)
				(hide yes)
			)
		)
		(property "Footprint" "antmicro-footprints:R_0402_1005Metric"
			(at 281.94 88.9 0)
			(effects
				(font
					(size 1.27 1.27)
					(thickness 0.15)
				)
				(justify left bottom)
				(hide yes)
			)
		)
		(property "Datasheet" "https://industrial.panasonic.com/cdbs/www-data/pdf/RDA0000/AOA0000C301.pdf"
			(at 281.94 91.44 0)
			(effects
				(font
					(size 1.27 1.27)
					(thickness 0.15)
				)
				(justify left bottom)
				(hide yes)
			)
		)
		(property "Description" "SMD Chip Resistor, Jumper, 0 ohm, 100 mW, 0402 [1005 Metric], Thick Film, General Purpose"
			(at 281.94 106.68 0)
			(effects
				(font
					(size 1.27 1.27)
				)
				(justify left bottom)
				(hide yes)
			)
		)
		(property "MPN" "ERJ2GE0R00X"
			(at 281.94 93.98 0)
			(effects
				(font
					(size 1.27 1.27)
					(thickness 0.15)
				)
				(justify left bottom)
				(hide yes)
			)
		)
		(property "Manufacturer" "Panasonic"
			(at 281.94 96.52 0)
			(effects
				(font
					(size 1.27 1.27)
					(thickness 0.15)
				)
				(justify left bottom)
				(hide yes)
			)
		)
		(property "License" "Apache-2.0"
			(at 281.94 99.06 0)
			(effects
				(font
					(size 1.27 1.27)
					(thickness 0.15)
				)
				(justify left bottom)
				(hide yes)
			)
		)
		(property "Author" "Antmicro"
			(at 281.94 101.6 0)
			(effects
				(font
					(size 1.27 1.27)
					(thickness 0.15)
				)
				(justify left bottom)
				(hide yes)
			)
		)
		(property "Val" "0R"
			(at 264.16 75.946 0)
			(effects
				(font
					(size 1.27 1.27)
					(thickness 0.15)
				)
			)
		)
		(property "Tolerance" "~"
			(at 281.94 83.82 0)
			(effects
				(font
					(size 1.27 1.27)
				)
				(justify left bottom)
				(hide yes)
			)
		)
		(property "Current" "1A"
			(at 281.94 104.14 0)
			(effects
				(font
					(size 1.27 1.27)
					(thickness 0.15)
				)
				(justify left bottom)
				(hide yes)
			)
		)
		(pin "2"
		)
		(pin "1"
		)
		(instances
			(project "OCuLink to 10GbE adapter"
				(path ""
					(reference "R10")
					(unit 1)
				)
			)
		)
	)
	(symbol
		(lib_id "antmicropower:VCC")
		(at 387.35 231.14 90)
		(unit 1)
		(exclude_from_sim no)
		(in_bom yes)
		(on_board yes)
		(dnp no)
		(fields_autoplaced yes)
		(property "Reference" "#PWR0306"
			(at 391.16 231.14 0)
			(effects
				(font
					(size 1.27 1.27)
				)
				(hide yes)
			)
		)
		(property "Value" "VCCD"
			(at 383.54 231.1399 90)
			(effects
				(font
					(size 1.27 1.27)
				)
				(justify left)
			)
		)
		(property "Footprint" ""
			(at 387.35 231.14 0)
			(effects
				(font
					(size 1.27 1.27)
				)
				(hide yes)
			)
		)
		(property "Datasheet" ""
			(at 387.35 231.14 0)
			(effects
				(font
					(size 1.27 1.27)
				)
				(hide yes)
			)
		)
		(property "Description" ""
			(at 387.35 231.14 0)
			(effects
				(font
					(size 1.27 1.27)
				)
				(hide yes)
			)
		)
		(pin "1"
		)
		(instances
			(project "oculink-to-10gbe-adapter"
				(path ""
					(reference "#PWR0306")
					(unit 1)
				)
			)
		)
	)
	(symbol
		(lib_id "antmicropower:+1V8")
		(at 400.05 99.06 0)
		(unit 1)
		(exclude_from_sim no)
		(in_bom yes)
		(on_board yes)
		(dnp no)
		(property "Reference" "#PWR023"
			(at 415.29 101.6 0)
			(effects
				(font
					(size 1.27 1.27)
					(thickness 0.15)
				)
				(justify left bottom)
				(hide yes)
			)
		)
		(property "Value" "+1V88"
			(at 400.05 95.25 0)
			(effects
				(font
					(size 1.27 1.27)
					(thickness 0.15)
				)
			)
		)
		(property "Footprint" ""
			(at 415.29 106.68 0)
			(effects
				(font
					(size 1.27 1.27)
					(thickness 0.15)
				)
				(justify left bottom)
				(hide yes)
			)
		)
		(property "Datasheet" ""
			(at 415.29 109.22 0)
			(effects
				(font
					(size 1.27 1.27)
					(thickness 0.15)
				)
				(justify left bottom)
				(hide yes)
			)
		)
		(property "Description" ""
			(at 400.05 99.06 0)
			(effects
				(font
					(size 1.27 1.27)
				)
				(hide yes)
			)
		)
		(property "Author" "Antmicro"
			(at 415.29 104.14 0)
			(effects
				(font
					(size 1.27 1.27)
					(thickness 0.15)
				)
				(justify left bottom)
				(hide yes)
			)
		)
		(property "License" "Apache-2.0"
			(at 415.29 106.68 0)
			(effects
				(font
					(size 1.27 1.27)
					(thickness 0.15)
				)
				(justify left bottom)
				(hide yes)
			)
		)
		(pin "1"
		)
		(instances
			(project "OCuLink to 10GbE adapter"
				(path ""
					(reference "#PWR023")
					(unit 1)
				)
			)
		)
	)
	(symbol
		(lib_id "antmicroTestPoints:TP_1mm_SMD")
		(at 391.16 238.76 0)
		(unit 1)
		(exclude_from_sim no)
		(in_bom no)
		(on_board yes)
		(dnp no)
		(fields_autoplaced yes)
		(property "Reference" "TP34"
			(at 396.24 238.76 0)
			(effects
				(font
					(size 1.27 1.27)
					(thickness 0.15)
				)
				(justify left)
			)
		)
		(property "Value" "TP_1mm_SMD"
			(at 406.4 246.38 0)
			(effects
				(font
					(size 1.27 1.27)
					(thickness 0.15)
				)
				(justify left bottom)
				(hide yes)
			)
		)
		(property "Footprint" "antmicro-footprints:TP_SMD_1mm"
			(at 406.4 248.92 0)
			(effects
				(font
					(size 1.27 1.27)
					(thickness 0.15)
				)
				(justify left bottom)
				(hide yes)
			)
		)
		(property "Datasheet" ""
			(at 408.94 251.46 0)
			(effects
				(font
					(size 1.27 1.27)
					(thickness 0.15)
				)
				(justify left bottom)
				(hide yes)
			)
		)
		(property "Description" "Test point 1mm SMD"
			(at 406.4 259.08 0)
			(effects
				(font
					(size 1.27 1.27)
				)
				(justify left bottom)
				(hide yes)
			)
		)
		(property "MPN" ""
			(at 391.16 238.76 0)
			(effects
				(font
					(size 1.27 1.27)
				)
				(hide yes)
			)
		)
		(property "Manufacturer" ""
			(at 391.16 238.76 0)
			(effects
				(font
					(size 1.27 1.27)
				)
				(hide yes)
			)
		)
		(property "Author" "Antmicro"
			(at 406.4 254 0)
			(effects
				(font
					(size 1.27 1.27)
					(thickness 0.15)
				)
				(justify left bottom)
				(hide yes)
			)
		)
		(property "License" "Apache-2.0"
			(at 406.4 256.54 0)
			(effects
				(font
					(size 1.27 1.27)
					(thickness 0.15)
				)
				(justify left bottom)
				(hide yes)
			)
		)
		(pin "1"
		)
		(instances
			(project "oculink-to-10gbe-adapter"
				(path ""
					(reference "TP34")
					(unit 1)
				)
			)
		)
	)
	(symbol
		(lib_id "antmicroFixedInductors:L_1u_10A_Bourns-SRP4021HMT")
		(at 314.96 139.7 0)
		(unit 1)
		(exclude_from_sim no)
		(in_bom yes)
		(on_board yes)
		(dnp no)
		(fields_autoplaced yes)
		(property "Reference" "L4"
			(at 317.5 134.62 0)
			(effects
				(font
					(size 1.27 1.27)
					(thickness 0.15)
				)
			)
		)
		(property "Value" "L_1u_10A_Bourns-SRP4021HMT"
			(at 330.2 149.86 0)
			(effects
				(font
					(size 1.27 1.27)
					(thickness 0.15)
				)
				(justify left bottom)
				(hide yes)
			)
		)
		(property "Footprint" "antmicro-footprints:L_Bourns-SRP4021HMT"
			(at 330.2 152.4 0)
			(effects
				(font
					(size 1.27 1.27)
					(thickness 0.15)
				)
				(justify left bottom)
				(hide yes)
			)
		)
		(property "Datasheet" "https://www.mouser.com/datasheet/2/54/Bourns_04_01_2025_SRP4021HMT_Datasheet-3580094.pdf"
			(at 330.2 154.94 0)
			(effects
				(font
					(size 1.27 1.27)
					(thickness 0.15)
				)
				(justify left bottom)
				(hide yes)
			)
		)
		(property "Description" "Power Inductors - SMD Ind,4.1x4.2x1.9mm,1uH+/-20%,10A, Shielded"
			(at 330.2 157.48 0)
			(effects
				(font
					(size 1.27 1.27)
					(thickness 0.15)
				)
				(justify left bottom)
				(hide yes)
			)
		)
		(property "Val" "1u/10A"
			(at 317.5 137.16 0)
			(effects
				(font
					(size 1.27 1.27)
					(thickness 0.15)
				)
			)
		)
		(property "Manufacturer" "Bourns"
			(at 330.2 160.02 0)
			(effects
				(font
					(size 1.27 1.27)
					(thickness 0.15)
				)
				(justify left bottom)
				(hide yes)
			)
		)
		(property "MPN" "SRP4021HMT-1R0M"
			(at 330.2 162.56 0)
			(effects
				(font
					(size 1.27 1.27)
					(thickness 0.15)
				)
				(justify left bottom)
				(hide yes)
			)
		)
		(property "ISat" ""
			(at 328.93 156.21 0)
			(effects
				(font
					(size 1.27 1.27)
				)
				(justify left)
				(hide yes)
			)
		)
		(property "Isat" "8A"
			(at 330.2 165.1 0)
			(effects
				(font
					(size 1.27 1.27)
					(thickness 0.15)
				)
				(justify left bottom)
				(hide yes)
			)
		)
		(property "IMax" ""
			(at 328.93 160.02 0)
			(effects
				(font
					(size 1.27 1.27)
					(thickness 0.15)
				)
				(justify left bottom)
				(hide yes)
			)
		)
		(property "Imax" "10A"
			(at 330.2 167.64 0)
			(effects
				(font
					(size 1.27 1.27)
					(thickness 0.15)
				)
				(justify left bottom)
				(hide yes)
			)
		)
		(property "Size" "4.2x4.1"
			(at 330.2 170.18 0)
			(effects
				(font
					(size 1.27 1.27)
					(thickness 0.15)
				)
				(justify left bottom)
				(hide yes)
			)
		)
		(property "Author" "Antmicro"
			(at 330.2 172.72 0)
			(effects
				(font
					(size 1.27 1.27)
					(thickness 0.15)
				)
				(justify left bottom)
				(hide yes)
			)
		)
		(property "License" "Apache-2.0"
			(at 330.2 175.26 0)
			(effects
				(font
					(size 1.27 1.27)
					(thickness 0.15)
				)
				(justify left bottom)
				(hide yes)
			)
		)
		(pin "1"
		)
		(pin "2"
		)
		(instances
			(project "OCuLink to 10GbE adapter"
				(path ""
					(reference "L4")
					(unit 1)
				)
			)
		)
	)
	(symbol
		(lib_id "antmicroCapacitors0603:C_22u_16V_0603")
		(at 344.17 76.2 90)
		(unit 1)
		(exclude_from_sim no)
		(in_bom yes)
		(on_board yes)
		(dnp no)
		(property "Reference" "C16"
			(at 346.202 72.39 90)
			(effects
				(font
					(size 1.27 1.27)
					(thickness 0.15)
				)
				(justify right)
			)
		)
		(property "Value" "C_22u_16V_0603"
			(at 354.33 55.88 0)
			(effects
				(font
					(size 1.27 1.27)
					(thickness 0.15)
				)
				(justify left bottom)
				(hide yes)
			)
		)
		(property "Footprint" "antmicro-footprints:C_0603_1608Metric_EIA"
			(at 356.87 55.88 0)
			(effects
				(font
					(size 1.27 1.27)
					(thickness 0.15)
				)
				(justify left bottom)
				(hide yes)
			)
		)
		(property "Datasheet" "https://product.samsungsem.com/mlcc/CL10A226MO7JZN.do"
			(at 359.41 55.88 0)
			(effects
				(font
					(size 1.27 1.27)
					(thickness 0.15)
				)
				(justify left bottom)
				(hide yes)
			)
		)
		(property "Description" "SMD Multilayer Ceramic Capacitor"
			(at 344.17 76.2 0)
			(effects
				(font
					(size 1.27 1.27)
				)
				(hide yes)
			)
		)
		(property "MPN" "CL10A226MO7JZNC"
			(at 361.95 55.88 0)
			(effects
				(font
					(size 1.27 1.27)
					(thickness 0.15)
				)
				(justify left bottom)
				(hide yes)
			)
		)
		(property "Manufacturer" "Samsung Electro-Mechanics"
			(at 364.49 55.88 0)
			(effects
				(font
					(size 1.27 1.27)
					(thickness 0.15)
				)
				(justify left bottom)
				(hide yes)
			)
		)
		(property "License" "Apache-2.0"
			(at 367.03 55.88 0)
			(effects
				(font
					(size 1.27 1.27)
					(thickness 0.15)
				)
				(justify left bottom)
				(hide yes)
			)
		)
		(property "Author" "Antmicro"
			(at 369.57 55.88 0)
			(effects
				(font
					(size 1.27 1.27)
					(thickness 0.15)
				)
				(justify left bottom)
				(hide yes)
			)
		)
		(property "Val" "22u"
			(at 346.202 74.93 90)
			(effects
				(font
					(size 1.27 1.27)
					(thickness 0.15)
				)
				(justify right)
			)
		)
		(property "Voltage" "16V"
			(at 346.71 76.1935 90)
			(effects
				(font
					(size 1.27 1.27)
				)
				(justify right)
				(hide yes)
			)
		)
		(property "Dielectric" ""
			(at 374.65 55.88 0)
			(effects
				(font
					(size 1.27 1.27)
				)
				(justify left bottom)
				(hide yes)
			)
		)
		(property "Public" "False"
			(at 377.19 55.88 0)
			(effects
				(font
					(size 1.27 1.27)
				)
				(justify left bottom)
				(hide yes)
			)
		)
		(pin "2"
		)
		(pin "1"
		)
		(instances
			(project "OCuLink to 10GbE adapter"
				(path ""
					(reference "C16")
					(unit 1)
				)
			)
		)
	)
	(symbol
		(lib_id "antmicroCapacitors0402:C_100n_0402")
		(at 307.34 106.68 270)
		(mirror x)
		(unit 1)
		(exclude_from_sim no)
		(in_bom yes)
		(on_board yes)
		(dnp no)
		(property "Reference" "C19"
			(at 309.118 103.124 90)
			(effects
				(font
					(size 1.27 1.27)
					(thickness 0.15)
				)
				(justify left)
			)
		)
		(property "Value" "C_100n_0402"
			(at 297.18 86.36 0)
			(effects
				(font
					(size 1.27 1.27)
					(thickness 0.15)
				)
				(justify left bottom)
				(hide yes)
			)
		)
		(property "Footprint" "antmicro-footprints:C_0402_1005Metric"
			(at 294.64 86.36 0)
			(effects
				(font
					(size 1.27 1.27)
					(thickness 0.15)
				)
				(justify left bottom)
				(hide yes)
			)
		)
		(property "Datasheet" "https://www.murata.com/products/productdetail?partno=GRM155R61H104KE14%23"
			(at 292.1 86.36 0)
			(effects
				(font
					(size 1.27 1.27)
					(thickness 0.15)
				)
				(justify left bottom)
				(hide yes)
			)
		)
		(property "Description" "SMD Multilayer Ceramic Capacitor, 0.1 µF, 50 V, 0402 [1005 Metric], ± 10%, X5R, GRM Series"
			(at 274.32 86.36 0)
			(effects
				(font
					(size 1.27 1.27)
				)
				(justify left bottom)
				(hide yes)
			)
		)
		(property "MPN" "GRM155R61H104KE14D"
			(at 289.56 86.36 0)
			(effects
				(font
					(size 1.27 1.27)
					(thickness 0.15)
				)
				(justify left bottom)
				(hide yes)
			)
		)
		(property "Manufacturer" "Murata"
			(at 287.02 86.36 0)
			(effects
				(font
					(size 1.27 1.27)
					(thickness 0.15)
				)
				(justify left bottom)
				(hide yes)
			)
		)
		(property "License" "Apache-2.0"
			(at 284.48 86.36 0)
			(effects
				(font
					(size 1.27 1.27)
					(thickness 0.15)
				)
				(justify left bottom)
				(hide yes)
			)
		)
		(property "Author" "Antmicro"
			(at 281.94 86.36 0)
			(effects
				(font
					(size 1.27 1.27)
					(thickness 0.15)
				)
				(justify left bottom)
				(hide yes)
			)
		)
		(property "Val" "100n"
			(at 309.118 105.664 90)
			(effects
				(font
					(size 1.27 1.27)
					(thickness 0.15)
				)
				(justify left)
			)
		)
		(property "Voltage" "50V"
			(at 279.4 86.36 0)
			(effects
				(font
					(size 1.27 1.27)
				)
				(justify left bottom)
				(hide yes)
			)
		)
		(property "Dielectric" "X5R"
			(at 276.86 86.36 0)
			(effects
				(font
					(size 1.27 1.27)
				)
				(justify left bottom)
				(hide yes)
			)
		)
		(pin "1"
		)
		(pin "2"
		)
		(instances
			(project "OCuLink to 10GbE adapter"
				(path ""
					(reference "C19")
					(unit 1)
				)
			)
		)
	)
	(symbol
		(lib_id "antmicroCapacitors0402:C_33p_0402")
		(at 327.66 147.32 270)
		(mirror x)
		(unit 1)
		(exclude_from_sim no)
		(in_bom no)
		(on_board yes)
		(dnp yes)
		(property "Reference" "C29"
			(at 325.882 143.51 90)
			(effects
				(font
					(size 1.27 1.27)
					(thickness 0.15)
				)
				(justify right)
			)
		)
		(property "Value" "C_33p_0402"
			(at 317.5 127 0)
			(effects
				(font
					(size 1.27 1.27)
					(thickness 0.15)
				)
				(justify left bottom)
				(hide yes)
			)
		)
		(property "Footprint" "antmicro-footprints:C_0402_1005Metric"
			(at 314.96 127 0)
			(effects
				(font
					(size 1.27 1.27)
					(thickness 0.15)
				)
				(justify left bottom)
				(hide yes)
			)
		)
		(property "Datasheet" "https://spicat.kyocera-avx.com/product/mlcc/chartview/04025A330FAT2A/"
			(at 312.42 127 0)
			(effects
				(font
					(size 1.27 1.27)
					(thickness 0.15)
				)
				(justify left bottom)
				(hide yes)
			)
		)
		(property "Description" "SMD Multilayer Ceramic Capacitor, 33 pF, 50 V, 0402 [1005 Metric], ± 5%, C0G / NP0, MC"
			(at 294.64 127 0)
			(effects
				(font
					(size 1.27 1.27)
				)
				(justify left bottom)
				(hide yes)
			)
		)
		(property "MPN" "04025A330FAT2A"
			(at 309.88 127 0)
			(effects
				(font
					(size 1.27 1.27)
					(thickness 0.15)
				)
				(justify left bottom)
				(hide yes)
			)
		)
		(property "Manufacturer" "KYOCERA AVX"
			(at 307.34 127 0)
			(effects
				(font
					(size 1.27 1.27)
					(thickness 0.15)
				)
				(justify left bottom)
				(hide yes)
			)
		)
		(property "License" "Apache-2.0"
			(at 304.8 127 0)
			(effects
				(font
					(size 1.27 1.27)
					(thickness 0.15)
				)
				(justify left bottom)
				(hide yes)
			)
		)
		(property "Author" "Antmicro"
			(at 302.26 127 0)
			(effects
				(font
					(size 1.27 1.27)
					(thickness 0.15)
				)
				(justify left bottom)
				(hide yes)
			)
		)
		(property "Val" "33p"
			(at 325.882 146.05 90)
			(effects
				(font
					(size 1.27 1.27)
					(thickness 0.15)
				)
				(justify right)
			)
		)
		(property "Voltage" ""
			(at 299.72 127 0)
			(effects
				(font
					(size 1.27 1.27)
				)
				(justify left bottom)
				(hide yes)
			)
		)
		(property "Dielectric" ""
			(at 297.18 127 0)
			(effects
				(font
					(size 1.27 1.27)
				)
				(justify left bottom)
				(hide yes)
			)
		)
		(pin "2"
		)
		(pin "1"
		)
		(instances
			(project "OCuLink to 10GbE adapter"
				(path ""
					(reference "C29")
					(unit 1)
				)
			)
		)
	)
	(symbol
		(lib_id "antmicropower:GND")
		(at 217.17 43.18 0)
		(unit 1)
		(exclude_from_sim no)
		(in_bom yes)
		(on_board yes)
		(dnp no)
		(property "Reference" "#PWR04"
			(at 226.06 45.72 0)
			(effects
				(font
					(size 1.27 1.27)
					(thickness 0.15)
				)
				(justify left bottom)
				(hide yes)
			)
		)
		(property "Value" "GND"
			(at 217.17 46.99 0)
			(effects
				(font
					(size 1.27 1.27)
					(thickness 0.15)
				)
			)
		)
		(property "Footprint" ""
			(at 226.06 50.8 0)
			(effects
				(font
					(size 1.27 1.27)
					(thickness 0.15)
				)
				(justify left bottom)
				(hide yes)
			)
		)
		(property "Datasheet" ""
			(at 226.06 55.88 0)
			(effects
				(font
					(size 1.27 1.27)
					(thickness 0.15)
				)
				(justify left bottom)
				(hide yes)
			)
		)
		(property "Description" ""
			(at 217.17 43.18 0)
			(effects
				(font
					(size 1.27 1.27)
				)
				(hide yes)
			)
		)
		(property "Author" "Antmicro"
			(at 226.06 50.8 0)
			(effects
				(font
					(size 1.27 1.27)
					(thickness 0.15)
				)
				(justify left bottom)
				(hide yes)
			)
		)
		(property "License" "Apache-2.0"
			(at 226.06 53.34 0)
			(effects
				(font
					(size 1.27 1.27)
					(thickness 0.15)
				)
				(justify left bottom)
				(hide yes)
			)
		)
		(pin "1"
		)
		(instances
			(project "OCuLink to 10GbE adapter"
				(path ""
					(reference "#PWR04")
					(unit 1)
				)
			)
		)
	)
	(symbol
		(lib_id "antmicropower:VCC")
		(at 400.05 60.96 0)
		(unit 1)
		(exclude_from_sim no)
		(in_bom yes)
		(on_board yes)
		(dnp no)
		(property "Reference" "#PWR013"
			(at 400.05 64.77 0)
			(effects
				(font
					(size 1.27 1.27)
				)
				(hide yes)
			)
		)
		(property "Value" "VCCD"
			(at 400.05 57.15 0)
			(effects
				(font
					(size 1.27 1.27)
				)
			)
		)
		(property "Footprint" ""
			(at 400.05 60.96 0)
			(effects
				(font
					(size 1.27 1.27)
				)
				(hide yes)
			)
		)
		(property "Datasheet" ""
			(at 400.05 60.96 0)
			(effects
				(font
					(size 1.27 1.27)
				)
				(hide yes)
			)
		)
		(property "Description" ""
			(at 400.05 60.96 0)
			(effects
				(font
					(size 1.27 1.27)
				)
				(hide yes)
			)
		)
		(pin "1"
		)
		(instances
			(project "OCuLink to 10GbE adapter"
				(path ""
					(reference "#PWR013")
					(unit 1)
				)
			)
		)
	)
	(symbol
		(lib_id "antmicroTestPoints:TP_1mm_SMD")
		(at 391.16 226.06 0)
		(unit 1)
		(exclude_from_sim no)
		(in_bom no)
		(on_board yes)
		(dnp no)
		(fields_autoplaced yes)
		(property "Reference" "TP29"
			(at 396.24 226.06 0)
			(effects
				(font
					(size 1.27 1.27)
					(thickness 0.15)
				)
				(justify left)
			)
		)
		(property "Value" "TP_1mm_SMD"
			(at 406.4 233.68 0)
			(effects
				(font
					(size 1.27 1.27)
					(thickness 0.15)
				)
				(justify left bottom)
				(hide yes)
			)
		)
		(property "Footprint" "antmicro-footprints:TP_SMD_1mm"
			(at 406.4 236.22 0)
			(effects
				(font
					(size 1.27 1.27)
					(thickness 0.15)
				)
				(justify left bottom)
				(hide yes)
			)
		)
		(property "Datasheet" ""
			(at 408.94 238.76 0)
			(effects
				(font
					(size 1.27 1.27)
					(thickness 0.15)
				)
				(justify left bottom)
				(hide yes)
			)
		)
		(property "Description" "Test point 1mm SMD"
			(at 406.4 246.38 0)
			(effects
				(font
					(size 1.27 1.27)
				)
				(justify left bottom)
				(hide yes)
			)
		)
		(property "MPN" ""
			(at 391.16 226.06 0)
			(effects
				(font
					(size 1.27 1.27)
				)
				(hide yes)
			)
		)
		(property "Manufacturer" ""
			(at 391.16 226.06 0)
			(effects
				(font
					(size 1.27 1.27)
				)
				(hide yes)
			)
		)
		(property "Author" "Antmicro"
			(at 406.4 241.3 0)
			(effects
				(font
					(size 1.27 1.27)
					(thickness 0.15)
				)
				(justify left bottom)
				(hide yes)
			)
		)
		(property "License" "Apache-2.0"
			(at 406.4 243.84 0)
			(effects
				(font
					(size 1.27 1.27)
					(thickness 0.15)
				)
				(justify left bottom)
				(hide yes)
			)
		)
		(pin "1"
		)
		(instances
			(project "oculink-to-10gbe-adapter"
				(path ""
					(reference "TP29")
					(unit 1)
				)
			)
		)
	)
	(symbol
		(lib_id "antmicropower:PWR_FLAG")
		(at 391.16 175.26 0)
		(unit 1)
		(exclude_from_sim no)
		(in_bom yes)
		(on_board yes)
		(dnp no)
		(property "Reference" "#FLG09"
			(at 391.16 173.355 0)
			(effects
				(font
					(size 1.27 1.27)
				)
				(hide yes)
			)
		)
		(property "Value" "PWR_FLAG"
			(at 391.16 171.45 0)
			(effects
				(font
					(size 1.27 1.27)
				)
			)
		)
		(property "Footprint" ""
			(at 391.16 175.26 0)
			(effects
				(font
					(size 1.27 1.27)
				)
				(hide yes)
			)
		)
		(property "Datasheet" ""
			(at 391.16 175.26 0)
			(effects
				(font
					(size 1.27 1.27)
				)
				(hide yes)
			)
		)
		(property "Description" ""
			(at 391.16 175.26 0)
			(effects
				(font
					(size 1.27 1.27)
				)
				(hide yes)
			)
		)
		(pin "1"
		)
		(instances
			(project "OCuLink to 10GbE adapter"
				(path ""
					(reference "#FLG09")
					(unit 1)
				)
			)
		)
	)
	(symbol
		(lib_id "antmicroTestPoints:TP_0.75mm_SMD")
		(at 350.52 24.13 90)
		(unit 1)
		(exclude_from_sim no)
		(in_bom no)
		(on_board yes)
		(dnp no)
		(property "Reference" "TP37"
			(at 350.52 19.05 90)
			(effects
				(font
					(size 1.27 1.27)
					(thickness 0.15)
				)
			)
		)
		(property "Value" "TP_0.75mm_SMD"
			(at 354.33 13.97 0)
			(effects
				(font
					(size 1.27 1.27)
					(thickness 0.15)
				)
				(justify left bottom)
				(hide yes)
			)
		)
		(property "Footprint" "antmicro-footprints:TP_SMD_0.75mm"
			(at 356.87 13.97 0)
			(effects
				(font
					(size 1.27 1.27)
					(thickness 0.15)
				)
				(justify left bottom)
				(hide yes)
			)
		)
		(property "Datasheet" ""
			(at 363.22 6.35 0)
			(effects
				(font
					(size 1.27 1.27)
					(thickness 0.15)
				)
				(justify left bottom)
				(hide yes)
			)
		)
		(property "Description" "SMT test point"
			(at 350.52 24.13 0)
			(effects
				(font
					(size 1.27 1.27)
				)
				(hide yes)
			)
		)
		(property "MPN" ""
			(at 361.95 13.335 0)
			(effects
				(font
					(size 1.27 1.27)
					(thickness 0.15)
				)
				(justify left bottom)
				(hide yes)
			)
		)
		(property "Manufacturer" ""
			(at 356.87 13.335 0)
			(effects
				(font
					(size 1.27 1.27)
					(thickness 0.15)
				)
				(justify left bottom)
				(hide yes)
			)
		)
		(property "Author" "Antmicro"
			(at 359.41 13.97 0)
			(effects
				(font
					(size 1.27 1.27)
					(thickness 0.15)
				)
				(justify left bottom)
				(hide yes)
			)
		)
		(property "License" "Apache-2.0"
			(at 361.95 13.97 0)
			(effects
				(font
					(size 1.27 1.27)
					(thickness 0.15)
				)
				(justify left bottom)
				(hide yes)
			)
		)
		(pin "1"
		)
		(instances
			(project "oculink-to-10gbe-adapter"
				(path ""
					(reference "TP37")
					(unit 1)
				)
			)
		)
	)
	(symbol
		(lib_id "antmicroTestPoints:TP_0.75mm_SMD")
		(at 350.52 176.53 90)
		(unit 1)
		(exclude_from_sim no)
		(in_bom no)
		(on_board yes)
		(dnp no)
		(property "Reference" "TP41"
			(at 350.52 171.45 90)
			(effects
				(font
					(size 1.27 1.27)
					(thickness 0.15)
				)
			)
		)
		(property "Value" "TP_0.75mm_SMD"
			(at 354.33 166.37 0)
			(effects
				(font
					(size 1.27 1.27)
					(thickness 0.15)
				)
				(justify left bottom)
				(hide yes)
			)
		)
		(property "Footprint" "antmicro-footprints:TP_SMD_0.75mm"
			(at 356.87 166.37 0)
			(effects
				(font
					(size 1.27 1.27)
					(thickness 0.15)
				)
				(justify left bottom)
				(hide yes)
			)
		)
		(property "Datasheet" ""
			(at 363.22 158.75 0)
			(effects
				(font
					(size 1.27 1.27)
					(thickness 0.15)
				)
				(justify left bottom)
				(hide yes)
			)
		)
		(property "Description" "SMT test point"
			(at 350.52 176.53 0)
			(effects
				(font
					(size 1.27 1.27)
				)
				(hide yes)
			)
		)
		(property "MPN" ""
			(at 361.95 165.735 0)
			(effects
				(font
					(size 1.27 1.27)
					(thickness 0.15)
				)
				(justify left bottom)
				(hide yes)
			)
		)
		(property "Manufacturer" ""
			(at 356.87 165.735 0)
			(effects
				(font
					(size 1.27 1.27)
					(thickness 0.15)
				)
				(justify left bottom)
				(hide yes)
			)
		)
		(property "Author" "Antmicro"
			(at 359.41 166.37 0)
			(effects
				(font
					(size 1.27 1.27)
					(thickness 0.15)
				)
				(justify left bottom)
				(hide yes)
			)
		)
		(property "License" "Apache-2.0"
			(at 361.95 166.37 0)
			(effects
				(font
					(size 1.27 1.27)
					(thickness 0.15)
				)
				(justify left bottom)
				(hide yes)
			)
		)
		(pin "1"
		)
		(instances
			(project "oculink-to-10gbe-adapter"
				(path ""
					(reference "TP41")
					(unit 1)
				)
			)
		)
	)
	(symbol
		(lib_id "antmicroResistors0402:R_1k_0402")
		(at 228.6 231.14 90)
		(unit 1)
		(exclude_from_sim no)
		(in_bom yes)
		(on_board yes)
		(dnp no)
		(property "Reference" "R146"
			(at 229.87 227.33 90)
			(effects
				(font
					(size 1.27 1.27)
					(thickness 0.15)
				)
				(justify right)
			)
		)
		(property "Value" "R_1k_0402"
			(at 241.3 210.82 0)
			(effects
				(font
					(size 1.27 1.27)
					(thickness 0.15)
				)
				(justify left bottom)
				(hide yes)
			)
		)
		(property "Footprint" "antmicro-footprints:R_0402_1005Metric"
			(at 243.84 210.82 0)
			(effects
				(font
					(size 1.27 1.27)
					(thickness 0.15)
				)
				(justify left bottom)
				(hide yes)
			)
		)
		(property "Datasheet" "https://www.bourns.com/docs/product-datasheets/cr.pdf"
			(at 246.38 210.82 0)
			(effects
				(font
					(size 1.27 1.27)
					(thickness 0.15)
				)
				(justify left bottom)
				(hide yes)
			)
		)
		(property "Description" "SMD Chip Resistor, 1 kohm, ± 1%, 63 mW, 0402 [1005 Metric], Thick Film, General Purpose"
			(at 259.08 210.82 0)
			(effects
				(font
					(size 1.27 1.27)
				)
				(justify left bottom)
				(hide yes)
			)
		)
		(property "MPN" "CR0402-FX-1001GLF"
			(at 248.92 210.82 0)
			(effects
				(font
					(size 1.27 1.27)
					(thickness 0.15)
				)
				(justify left bottom)
				(hide yes)
			)
		)
		(property "Manufacturer" "Bourns"
			(at 251.46 210.82 0)
			(effects
				(font
					(size 1.27 1.27)
					(thickness 0.15)
				)
				(justify left bottom)
				(hide yes)
			)
		)
		(property "License" "Apache-2.0"
			(at 254 210.82 0)
			(effects
				(font
					(size 1.27 1.27)
					(thickness 0.15)
				)
				(justify left bottom)
				(hide yes)
			)
		)
		(property "Author" "Antmicro"
			(at 256.54 210.82 0)
			(effects
				(font
					(size 1.27 1.27)
					(thickness 0.15)
				)
				(justify left bottom)
				(hide yes)
			)
		)
		(property "Val" "1k"
			(at 229.87 229.87 90)
			(effects
				(font
					(size 1.27 1.27)
					(thickness 0.15)
				)
				(justify right)
			)
		)
		(property "Tolerance" "1%"
			(at 238.76 210.82 0)
			(effects
				(font
					(size 1.27 1.27)
				)
				(justify left bottom)
				(hide yes)
			)
		)
		(pin "1"
		)
		(pin "2"
		)
		(instances
			(project "oculink-to-10gbe-adapter"
				(path ""
					(reference "R146")
					(unit 1)
				)
			)
		)
	)
	(symbol
		(lib_id "antmicropower:GND")
		(at 364.49 157.48 0)
		(unit 1)
		(exclude_from_sim no)
		(in_bom yes)
		(on_board yes)
		(dnp no)
		(property "Reference" "#PWR0336"
			(at 373.38 160.02 0)
			(effects
				(font
					(size 1.27 1.27)
					(thickness 0.15)
				)
				(justify left bottom)
				(hide yes)
			)
		)
		(property "Value" "GND"
			(at 364.49 161.29 0)
			(effects
				(font
					(size 1.27 1.27)
					(thickness 0.15)
				)
			)
		)
		(property "Footprint" ""
			(at 373.38 165.1 0)
			(effects
				(font
					(size 1.27 1.27)
					(thickness 0.15)
				)
				(justify left bottom)
				(hide yes)
			)
		)
		(property "Datasheet" ""
			(at 373.38 170.18 0)
			(effects
				(font
					(size 1.27 1.27)
					(thickness 0.15)
				)
				(justify left bottom)
				(hide yes)
			)
		)
		(property "Description" ""
			(at 364.49 157.48 0)
			(effects
				(font
					(size 1.27 1.27)
				)
				(hide yes)
			)
		)
		(property "Author" "Antmicro"
			(at 373.38 165.1 0)
			(effects
				(font
					(size 1.27 1.27)
					(thickness 0.15)
				)
				(justify left bottom)
				(hide yes)
			)
		)
		(property "License" "Apache-2.0"
			(at 373.38 167.64 0)
			(effects
				(font
					(size 1.27 1.27)
					(thickness 0.15)
				)
				(justify left bottom)
				(hide yes)
			)
		)
		(pin "1"
		)
		(instances
			(project "OCuLink to 10GbE adapter"
				(path ""
					(reference "#PWR0336")
					(unit 1)
				)
			)
		)
	)
	(symbol
		(lib_id "antmicroCapacitors0603:C_22u_16V_0603")
		(at 227.33 76.2 270)
		(mirror x)
		(unit 1)
		(exclude_from_sim no)
		(in_bom yes)
		(on_board yes)
		(dnp no)
		(property "Reference" "C13"
			(at 225.552 72.39 90)
			(effects
				(font
					(size 1.27 1.27)
					(thickness 0.15)
				)
				(justify right)
			)
		)
		(property "Value" "C_22u_16V_0603"
			(at 217.17 55.88 0)
			(effects
				(font
					(size 1.27 1.27)
					(thickness 0.15)
				)
				(justify left bottom)
				(hide yes)
			)
		)
		(property "Footprint" "antmicro-footprints:C_0603_1608Metric_EIA"
			(at 214.63 55.88 0)
			(effects
				(font
					(size 1.27 1.27)
					(thickness 0.15)
				)
				(justify left bottom)
				(hide yes)
			)
		)
		(property "Datasheet" "https://product.samsungsem.com/mlcc/CL10A226MO7JZN.do"
			(at 212.09 55.88 0)
			(effects
				(font
					(size 1.27 1.27)
					(thickness 0.15)
				)
				(justify left bottom)
				(hide yes)
			)
		)
		(property "Description" "SMD Multilayer Ceramic Capacitor"
			(at 227.33 76.2 0)
			(effects
				(font
					(size 1.27 1.27)
				)
				(hide yes)
			)
		)
		(property "MPN" "CL10A226MO7JZNC"
			(at 209.55 55.88 0)
			(effects
				(font
					(size 1.27 1.27)
					(thickness 0.15)
				)
				(justify left bottom)
				(hide yes)
			)
		)
		(property "Manufacturer" "Samsung Electro-Mechanics"
			(at 207.01 55.88 0)
			(effects
				(font
					(size 1.27 1.27)
					(thickness 0.15)
				)
				(justify left bottom)
				(hide yes)
			)
		)
		(property "License" "Apache-2.0"
			(at 204.47 55.88 0)
			(effects
				(font
					(size 1.27 1.27)
					(thickness 0.15)
				)
				(justify left bottom)
				(hide yes)
			)
		)
		(property "Author" "Antmicro"
			(at 201.93 55.88 0)
			(effects
				(font
					(size 1.27 1.27)
					(thickness 0.15)
				)
				(justify left bottom)
				(hide yes)
			)
		)
		(property "Val" "22u"
			(at 225.552 74.93 90)
			(effects
				(font
					(size 1.27 1.27)
					(thickness 0.15)
				)
				(justify right)
			)
		)
		(property "Voltage" "16V"
			(at 224.79 76.1935 90)
			(effects
				(font
					(size 1.27 1.27)
				)
				(justify right)
				(hide yes)
			)
		)
		(property "Dielectric" ""
			(at 196.85 55.88 0)
			(effects
				(font
					(size 1.27 1.27)
				)
				(justify left bottom)
				(hide yes)
			)
		)
		(property "Public" "False"
			(at 194.31 55.88 0)
			(effects
				(font
					(size 1.27 1.27)
				)
				(justify left bottom)
				(hide yes)
			)
		)
		(pin "2"
		)
		(pin "1"
		)
		(instances
			(project "OCuLink to 10GbE adapter"
				(path ""
					(reference "C13")
					(unit 1)
				)
			)
		)
	)
	(symbol
		(lib_id "antmicroTransistorsBipolarSingle:DTC014T_SOT-416")
		(at 195.58 238.76 0)
		(unit 1)
		(exclude_from_sim no)
		(in_bom yes)
		(on_board yes)
		(dnp no)
		(property "Reference" "Q5"
			(at 204.978 240.03 0)
			(effects
				(font
					(size 1.27 1.27)
					(thickness 0.15)
				)
				(justify left)
			)
		)
		(property "Value" "DTC014T_SOT-416"
			(at 220.98 246.38 0)
			(effects
				(font
					(size 1.27 1.27)
					(thickness 0.15)
				)
				(justify left bottom)
				(hide yes)
			)
		)
		(property "Footprint" "antmicro-footprints:SOT-416"
			(at 220.98 248.92 0)
			(effects
				(font
					(size 1.27 1.27)
					(thickness 0.15)
				)
				(justify left bottom)
				(hide yes)
			)
		)
		(property "Datasheet" "https://www.rohm.com/datasheet?p=DTC014TEB&dist=Mouser&media=referral&source=mouser.com&campaign=Mouser"
			(at 220.98 251.46 0)
			(effects
				(font
					(size 1.27 1.27)
					(thickness 0.15)
				)
				(justify left bottom)
				(hide yes)
			)
		)
		(property "Description" "Bipolar (BJT) Single Transistor with built-in base resistor, NPN, 50V, 100mA, 150mW, SOT-416FL, Surface Mount"
			(at 220.98 264.16 0)
			(effects
				(font
					(size 1.27 1.27)
				)
				(justify left bottom)
				(hide yes)
			)
		)
		(property "Manufacturer" "ROHM Semiconductor"
			(at 220.98 254 0)
			(effects
				(font
					(size 1.27 1.27)
					(thickness 0.15)
				)
				(justify left bottom)
				(hide yes)
			)
		)
		(property "MPN" "DTC014TEBTL"
			(at 204.978 242.57 0)
			(effects
				(font
					(size 1.27 1.27)
					(thickness 0.15)
				)
				(justify left)
			)
		)
		(property "Author" "Antmicro"
			(at 220.98 259.08 0)
			(effects
				(font
					(size 1.27 1.27)
					(thickness 0.15)
				)
				(justify left bottom)
				(hide yes)
			)
		)
		(property "License" "Apache-2.0"
			(at 220.98 261.62 0)
			(effects
				(font
					(size 1.27 1.27)
					(thickness 0.15)
				)
				(justify left bottom)
				(hide yes)
			)
		)
		(pin "1"
		)
		(pin "2"
		)
		(pin "3"
		)
		(instances
			(project "oculink-to-10gbe-adapter"
				(path ""
					(reference "Q5")
					(unit 1)
				)
			)
		)
	)
	(symbol
		(lib_id "antmicroResistors0402:R_100k_0402")
		(at 256.54 38.1 270)
		(mirror x)
		(unit 1)
		(exclude_from_sim no)
		(in_bom yes)
		(on_board yes)
		(dnp no)
		(property "Reference" "R4"
			(at 255.27 34.29 90)
			(effects
				(font
					(size 1.27 1.27)
					(thickness 0.15)
				)
				(justify right)
			)
		)
		(property "Value" "R_100k_0402"
			(at 243.84 17.78 0)
			(effects
				(font
					(size 1.27 1.27)
					(thickness 0.15)
				)
				(justify left bottom)
				(hide yes)
			)
		)
		(property "Footprint" "antmicro-footprints:R_0402_1005Metric"
			(at 241.3 17.78 0)
			(effects
				(font
					(size 1.27 1.27)
					(thickness 0.15)
				)
				(justify left bottom)
				(hide yes)
			)
		)
		(property "Datasheet" "https://www.bourns.com/docs/product-datasheets/cr.pdf"
			(at 238.76 17.78 0)
			(effects
				(font
					(size 1.27 1.27)
					(thickness 0.15)
				)
				(justify left bottom)
				(hide yes)
			)
		)
		(property "Description" "SMD Chip Resistor, 100 kohm, ± 1%, 62.5 mW, 0402 [1005 Metric], Thick Film, General Purpose"
			(at 226.06 17.78 0)
			(effects
				(font
					(size 1.27 1.27)
				)
				(justify left bottom)
				(hide yes)
			)
		)
		(property "MPN" "CR0402-FX-1003GLF"
			(at 236.22 17.78 0)
			(effects
				(font
					(size 1.27 1.27)
					(thickness 0.15)
				)
				(justify left bottom)
				(hide yes)
			)
		)
		(property "Manufacturer" "Bourns"
			(at 233.68 17.78 0)
			(effects
				(font
					(size 1.27 1.27)
					(thickness 0.15)
				)
				(justify left bottom)
				(hide yes)
			)
		)
		(property "License" "Apache-2.0"
			(at 231.14 17.78 0)
			(effects
				(font
					(size 1.27 1.27)
					(thickness 0.15)
				)
				(justify left bottom)
				(hide yes)
			)
		)
		(property "Author" "Antmicro"
			(at 228.6 17.78 0)
			(effects
				(font
					(size 1.27 1.27)
					(thickness 0.15)
				)
				(justify left bottom)
				(hide yes)
			)
		)
		(property "Val" "100k"
			(at 255.27 36.83 90)
			(effects
				(font
					(size 1.27 1.27)
					(thickness 0.15)
				)
				(justify right)
			)
		)
		(property "Tolerance" "1%"
			(at 246.38 17.78 0)
			(effects
				(font
					(size 1.27 1.27)
				)
				(justify left bottom)
				(hide yes)
			)
		)
		(pin "1"
		)
		(pin "2"
		)
		(instances
			(project ""
				(path ""
					(reference "R4")
					(unit 1)
				)
			)
		)
	)
	(symbol
		(lib_id "antmicroResistors0402:R_100k_0402")
		(at 256.54 76.2 270)
		(mirror x)
		(unit 1)
		(exclude_from_sim no)
		(in_bom yes)
		(on_board yes)
		(dnp no)
		(property "Reference" "R11"
			(at 255.27 72.39 90)
			(effects
				(font
					(size 1.27 1.27)
					(thickness 0.15)
				)
				(justify right)
			)
		)
		(property "Value" "R_100k_0402"
			(at 243.84 55.88 0)
			(effects
				(font
					(size 1.27 1.27)
					(thickness 0.15)
				)
				(justify left bottom)
				(hide yes)
			)
		)
		(property "Footprint" "antmicro-footprints:R_0402_1005Metric"
			(at 241.3 55.88 0)
			(effects
				(font
					(size 1.27 1.27)
					(thickness 0.15)
				)
				(justify left bottom)
				(hide yes)
			)
		)
		(property "Datasheet" "https://www.bourns.com/docs/product-datasheets/cr.pdf"
			(at 238.76 55.88 0)
			(effects
				(font
					(size 1.27 1.27)
					(thickness 0.15)
				)
				(justify left bottom)
				(hide yes)
			)
		)
		(property "Description" "SMD Chip Resistor, 100 kohm, ± 1%, 62.5 mW, 0402 [1005 Metric], Thick Film, General Purpose"
			(at 226.06 55.88 0)
			(effects
				(font
					(size 1.27 1.27)
				)
				(justify left bottom)
				(hide yes)
			)
		)
		(property "MPN" "CR0402-FX-1003GLF"
			(at 236.22 55.88 0)
			(effects
				(font
					(size 1.27 1.27)
					(thickness 0.15)
				)
				(justify left bottom)
				(hide yes)
			)
		)
		(property "Manufacturer" "Bourns"
			(at 233.68 55.88 0)
			(effects
				(font
					(size 1.27 1.27)
					(thickness 0.15)
				)
				(justify left bottom)
				(hide yes)
			)
		)
		(property "License" "Apache-2.0"
			(at 231.14 55.88 0)
			(effects
				(font
					(size 1.27 1.27)
					(thickness 0.15)
				)
				(justify left bottom)
				(hide yes)
			)
		)
		(property "Author" "Antmicro"
			(at 228.6 55.88 0)
			(effects
				(font
					(size 1.27 1.27)
					(thickness 0.15)
				)
				(justify left bottom)
				(hide yes)
			)
		)
		(property "Val" "100k"
			(at 255.27 74.93 90)
			(effects
				(font
					(size 1.27 1.27)
					(thickness 0.15)
				)
				(justify right)
			)
		)
		(property "Tolerance" "1%"
			(at 246.38 55.88 0)
			(effects
				(font
					(size 1.27 1.27)
				)
				(justify left bottom)
				(hide yes)
			)
		)
		(pin "1"
		)
		(pin "2"
		)
		(instances
			(project "OCuLink to 10GbE adapter"
				(path ""
					(reference "R11")
					(unit 1)
				)
			)
		)
	)
	(symbol
		(lib_id "antmicroCapacitors0402:C_100n_0402")
		(at 374.65 38.1 90)
		(unit 1)
		(exclude_from_sim no)
		(in_bom yes)
		(on_board yes)
		(dnp no)
		(property "Reference" "C9"
			(at 376.428 34.29 90)
			(effects
				(font
					(size 1.27 1.27)
					(thickness 0.15)
				)
				(justify right)
			)
		)
		(property "Value" "C_100n_0402"
			(at 384.81 17.78 0)
			(effects
				(font
					(size 1.27 1.27)
					(thickness 0.15)
				)
				(justify left bottom)
				(hide yes)
			)
		)
		(property "Footprint" "antmicro-footprints:C_0402_1005Metric"
			(at 387.35 17.78 0)
			(effects
				(font
					(size 1.27 1.27)
					(thickness 0.15)
				)
				(justify left bottom)
				(hide yes)
			)
		)
		(property "Datasheet" "https://www.murata.com/products/productdetail?partno=GRM155R61H104KE14%23"
			(at 389.89 17.78 0)
			(effects
				(font
					(size 1.27 1.27)
					(thickness 0.15)
				)
				(justify left bottom)
				(hide yes)
			)
		)
		(property "Description" "SMD Multilayer Ceramic Capacitor, 0.1 µF, 50 V, 0402 [1005 Metric], ± 10%, X5R, GRM Series"
			(at 407.67 17.78 0)
			(effects
				(font
					(size 1.27 1.27)
				)
				(justify left bottom)
				(hide yes)
			)
		)
		(property "MPN" "GRM155R61H104KE14D"
			(at 392.43 17.78 0)
			(effects
				(font
					(size 1.27 1.27)
					(thickness 0.15)
				)
				(justify left bottom)
				(hide yes)
			)
		)
		(property "Manufacturer" "Murata"
			(at 394.97 17.78 0)
			(effects
				(font
					(size 1.27 1.27)
					(thickness 0.15)
				)
				(justify left bottom)
				(hide yes)
			)
		)
		(property "License" "Apache-2.0"
			(at 397.51 17.78 0)
			(effects
				(font
					(size 1.27 1.27)
					(thickness 0.15)
				)
				(justify left bottom)
				(hide yes)
			)
		)
		(property "Author" "Antmicro"
			(at 400.05 17.78 0)
			(effects
				(font
					(size 1.27 1.27)
					(thickness 0.15)
				)
				(justify left bottom)
				(hide yes)
			)
		)
		(property "Val" "100n"
			(at 376.428 36.83 90)
			(effects
				(font
					(size 1.27 1.27)
					(thickness 0.15)
				)
				(justify right)
			)
		)
		(property "Voltage" "50V"
			(at 402.59 17.78 0)
			(effects
				(font
					(size 1.27 1.27)
				)
				(justify left bottom)
				(hide yes)
			)
		)
		(property "Dielectric" "X5R"
			(at 405.13 17.78 0)
			(effects
				(font
					(size 1.27 1.27)
				)
				(justify left bottom)
				(hide yes)
			)
		)
		(pin "1"
		)
		(pin "2"
		)
		(instances
			(project "OCuLink to 10GbE adapter"
				(path ""
					(reference "C9")
					(unit 1)
				)
			)
		)
	)
	(symbol
		(lib_id "antmicropower:PWR_FLAG")
		(at 74.93 118.11 0)
		(unit 1)
		(exclude_from_sim no)
		(in_bom yes)
		(on_board yes)
		(dnp no)
		(property "Reference" "#FLG06"
			(at 74.93 116.205 0)
			(effects
				(font
					(size 1.27 1.27)
				)
				(hide yes)
			)
		)
		(property "Value" "PWR_FLAG"
			(at 74.93 114.3 0)
			(effects
				(font
					(size 1.27 1.27)
				)
			)
		)
		(property "Footprint" ""
			(at 74.93 118.11 0)
			(effects
				(font
					(size 1.27 1.27)
				)
				(hide yes)
			)
		)
		(property "Datasheet" ""
			(at 74.93 118.11 0)
			(effects
				(font
					(size 1.27 1.27)
				)
				(hide yes)
			)
		)
		(property "Description" ""
			(at 74.93 118.11 0)
			(effects
				(font
					(size 1.27 1.27)
				)
				(hide yes)
			)
		)
		(pin "1"
		)
		(instances
			(project "OCuLink to 10GbE adapter"
				(path ""
					(reference "#FLG06")
					(unit 1)
				)
			)
		)
	)
	(symbol
		(lib_id "antmicroCapacitors0603:C_22u_16V_0603")
		(at 344.17 152.4 90)
		(unit 1)
		(exclude_from_sim no)
		(in_bom yes)
		(on_board yes)
		(dnp no)
		(property "Reference" "C34"
			(at 346.202 148.59 90)
			(effects
				(font
					(size 1.27 1.27)
					(thickness 0.15)
				)
				(justify right)
			)
		)
		(property "Value" "C_22u_16V_0603"
			(at 354.33 132.08 0)
			(effects
				(font
					(size 1.27 1.27)
					(thickness 0.15)
				)
				(justify left bottom)
				(hide yes)
			)
		)
		(property "Footprint" "antmicro-footprints:C_0603_1608Metric_EIA"
			(at 356.87 132.08 0)
			(effects
				(font
					(size 1.27 1.27)
					(thickness 0.15)
				)
				(justify left bottom)
				(hide yes)
			)
		)
		(property "Datasheet" "https://product.samsungsem.com/mlcc/CL10A226MO7JZN.do"
			(at 359.41 132.08 0)
			(effects
				(font
					(size 1.27 1.27)
					(thickness 0.15)
				)
				(justify left bottom)
				(hide yes)
			)
		)
		(property "Description" "SMD Multilayer Ceramic Capacitor"
			(at 344.17 152.4 0)
			(effects
				(font
					(size 1.27 1.27)
				)
				(hide yes)
			)
		)
		(property "MPN" "CL10A226MO7JZNC"
			(at 361.95 132.08 0)
			(effects
				(font
					(size 1.27 1.27)
					(thickness 0.15)
				)
				(justify left bottom)
				(hide yes)
			)
		)
		(property "Manufacturer" "Samsung Electro-Mechanics"
			(at 364.49 132.08 0)
			(effects
				(font
					(size 1.27 1.27)
					(thickness 0.15)
				)
				(justify left bottom)
				(hide yes)
			)
		)
		(property "License" "Apache-2.0"
			(at 367.03 132.08 0)
			(effects
				(font
					(size 1.27 1.27)
					(thickness 0.15)
				)
				(justify left bottom)
				(hide yes)
			)
		)
		(property "Author" "Antmicro"
			(at 369.57 132.08 0)
			(effects
				(font
					(size 1.27 1.27)
					(thickness 0.15)
				)
				(justify left bottom)
				(hide yes)
			)
		)
		(property "Val" "22u"
			(at 346.202 151.13 90)
			(effects
				(font
					(size 1.27 1.27)
					(thickness 0.15)
				)
				(justify right)
			)
		)
		(property "Voltage" "16V"
			(at 346.71 152.3935 90)
			(effects
				(font
					(size 1.27 1.27)
				)
				(justify right)
				(hide yes)
			)
		)
		(property "Dielectric" ""
			(at 374.65 132.08 0)
			(effects
				(font
					(size 1.27 1.27)
				)
				(justify left bottom)
				(hide yes)
			)
		)
		(property "Public" "False"
			(at 377.19 132.08 0)
			(effects
				(font
					(size 1.27 1.27)
				)
				(justify left bottom)
				(hide yes)
			)
		)
		(pin "2"
		)
		(pin "1"
		)
		(instances
			(project "OCuLink to 10GbE adapter"
				(path ""
					(reference "C34")
					(unit 1)
				)
			)
		)
	)
	(symbol
		(lib_id "antmicropower:VCC")
		(at 196.85 22.86 0)
		(unit 1)
		(exclude_from_sim no)
		(in_bom yes)
		(on_board yes)
		(dnp no)
		(property "Reference" "#PWR0354"
			(at 196.85 26.67 0)
			(effects
				(font
					(size 1.27 1.27)
				)
				(hide yes)
			)
		)
		(property "Value" "VCC"
			(at 196.85 19.05 0)
			(effects
				(font
					(size 1.27 1.27)
				)
			)
		)
		(property "Footprint" ""
			(at 196.85 22.86 0)
			(effects
				(font
					(size 1.27 1.27)
				)
				(hide yes)
			)
		)
		(property "Datasheet" ""
			(at 196.85 22.86 0)
			(effects
				(font
					(size 1.27 1.27)
				)
				(hide yes)
			)
		)
		(property "Description" ""
			(at 196.85 29.21 0)
			(effects
				(font
					(size 1.27 1.27)
				)
				(justify left bottom)
				(hide yes)
			)
		)
		(pin "1"
		)
		(instances
			(project "oculink-to-10gbe-adapter"
				(path ""
					(reference "#PWR0354")
					(unit 1)
				)
			)
		)
	)
	(symbol
		(lib_id "antmicroTestPoints:TP_0.75mm_SMD")
		(at 350.52 62.23 90)
		(unit 1)
		(exclude_from_sim no)
		(in_bom no)
		(on_board yes)
		(dnp no)
		(property "Reference" "TP38"
			(at 350.52 57.15 90)
			(effects
				(font
					(size 1.27 1.27)
					(thickness 0.15)
				)
			)
		)
		(property "Value" "TP_0.75mm_SMD"
			(at 354.33 52.07 0)
			(effects
				(font
					(size 1.27 1.27)
					(thickness 0.15)
				)
				(justify left bottom)
				(hide yes)
			)
		)
		(property "Footprint" "antmicro-footprints:TP_SMD_0.75mm"
			(at 356.87 52.07 0)
			(effects
				(font
					(size 1.27 1.27)
					(thickness 0.15)
				)
				(justify left bottom)
				(hide yes)
			)
		)
		(property "Datasheet" ""
			(at 363.22 44.45 0)
			(effects
				(font
					(size 1.27 1.27)
					(thickness 0.15)
				)
				(justify left bottom)
				(hide yes)
			)
		)
		(property "Description" "SMT test point"
			(at 350.52 62.23 0)
			(effects
				(font
					(size 1.27 1.27)
				)
				(hide yes)
			)
		)
		(property "MPN" ""
			(at 361.95 51.435 0)
			(effects
				(font
					(size 1.27 1.27)
					(thickness 0.15)
				)
				(justify left bottom)
				(hide yes)
			)
		)
		(property "Manufacturer" ""
			(at 356.87 51.435 0)
			(effects
				(font
					(size 1.27 1.27)
					(thickness 0.15)
				)
				(justify left bottom)
				(hide yes)
			)
		)
		(property "Author" "Antmicro"
			(at 359.41 52.07 0)
			(effects
				(font
					(size 1.27 1.27)
					(thickness 0.15)
				)
				(justify left bottom)
				(hide yes)
			)
		)
		(property "License" "Apache-2.0"
			(at 361.95 52.07 0)
			(effects
				(font
					(size 1.27 1.27)
					(thickness 0.15)
				)
				(justify left bottom)
				(hide yes)
			)
		)
		(pin "1"
		)
		(instances
			(project "oculink-to-10gbe-adapter"
				(path ""
					(reference "TP38")
					(unit 1)
				)
			)
		)
	)
	(symbol
		(lib_id "antmicropower:GND")
		(at 344.17 43.18 0)
		(unit 1)
		(exclude_from_sim no)
		(in_bom yes)
		(on_board yes)
		(dnp no)
		(property "Reference" "#PWR010"
			(at 353.06 45.72 0)
			(effects
				(font
					(size 1.27 1.27)
					(thickness 0.15)
				)
				(justify left bottom)
				(hide yes)
			)
		)
		(property "Value" "GND"
			(at 344.17 46.99 0)
			(effects
				(font
					(size 1.27 1.27)
					(thickness 0.15)
				)
			)
		)
		(property "Footprint" ""
			(at 353.06 50.8 0)
			(effects
				(font
					(size 1.27 1.27)
					(thickness 0.15)
				)
				(justify left bottom)
				(hide yes)
			)
		)
		(property "Datasheet" ""
			(at 353.06 55.88 0)
			(effects
				(font
					(size 1.27 1.27)
					(thickness 0.15)
				)
				(justify left bottom)
				(hide yes)
			)
		)
		(property "Description" ""
			(at 344.17 43.18 0)
			(effects
				(font
					(size 1.27 1.27)
				)
				(hide yes)
			)
		)
		(property "Author" "Antmicro"
			(at 353.06 50.8 0)
			(effects
				(font
					(size 1.27 1.27)
					(thickness 0.15)
				)
				(justify left bottom)
				(hide yes)
			)
		)
		(property "License" "Apache-2.0"
			(at 353.06 53.34 0)
			(effects
				(font
					(size 1.27 1.27)
					(thickness 0.15)
				)
				(justify left bottom)
				(hide yes)
			)
		)
		(pin "1"
		)
		(instances
			(project "OCuLink to 10GbE adapter"
				(path ""
					(reference "#PWR010")
					(unit 1)
				)
			)
		)
	)
	(symbol
		(lib_id "antmicroTestPoints:TP_1mm_SMD")
		(at 391.16 223.52 0)
		(unit 1)
		(exclude_from_sim no)
		(in_bom no)
		(on_board yes)
		(dnp no)
		(fields_autoplaced yes)
		(property "Reference" "TP28"
			(at 396.24 223.52 0)
			(effects
				(font
					(size 1.27 1.27)
					(thickness 0.15)
				)
				(justify left)
			)
		)
		(property "Value" "TP_1mm_SMD"
			(at 406.4 231.14 0)
			(effects
				(font
					(size 1.27 1.27)
					(thickness 0.15)
				)
				(justify left bottom)
				(hide yes)
			)
		)
		(property "Footprint" "antmicro-footprints:TP_SMD_1mm"
			(at 406.4 233.68 0)
			(effects
				(font
					(size 1.27 1.27)
					(thickness 0.15)
				)
				(justify left bottom)
				(hide yes)
			)
		)
		(property "Datasheet" ""
			(at 408.94 236.22 0)
			(effects
				(font
					(size 1.27 1.27)
					(thickness 0.15)
				)
				(justify left bottom)
				(hide yes)
			)
		)
		(property "Description" "Test point 1mm SMD"
			(at 406.4 243.84 0)
			(effects
				(font
					(size 1.27 1.27)
				)
				(justify left bottom)
				(hide yes)
			)
		)
		(property "MPN" ""
			(at 391.16 223.52 0)
			(effects
				(font
					(size 1.27 1.27)
				)
				(hide yes)
			)
		)
		(property "Manufacturer" ""
			(at 391.16 223.52 0)
			(effects
				(font
					(size 1.27 1.27)
				)
				(hide yes)
			)
		)
		(property "Author" "Antmicro"
			(at 406.4 238.76 0)
			(effects
				(font
					(size 1.27 1.27)
					(thickness 0.15)
				)
				(justify left bottom)
				(hide yes)
			)
		)
		(property "License" "Apache-2.0"
			(at 406.4 241.3 0)
			(effects
				(font
					(size 1.27 1.27)
					(thickness 0.15)
				)
				(justify left bottom)
				(hide yes)
			)
		)
		(pin "1"
		)
		(instances
			(project "oculink-to-10gbe-adapter"
				(path ""
					(reference "TP28")
					(unit 1)
				)
			)
		)
	)
	(symbol
		(lib_id "antmicroResistors0402:R_90k9_0402")
		(at 332.74 33.02 90)
		(unit 1)
		(exclude_from_sim no)
		(in_bom yes)
		(on_board yes)
		(dnp no)
		(property "Reference" "R3"
			(at 334.01 29.21 90)
			(effects
				(font
					(size 1.27 1.27)
					(thickness 0.15)
				)
				(justify right)
			)
		)
		(property "Value" "R_90k9_0402"
			(at 345.44 12.7 0)
			(effects
				(font
					(size 1.27 1.27)
					(thickness 0.15)
				)
				(justify left bottom)
				(hide yes)
			)
		)
		(property "Footprint" "antmicro-footprints:R_0402_1005Metric"
			(at 347.98 12.7 0)
			(effects
				(font
					(size 1.27 1.27)
					(thickness 0.15)
				)
				(justify left bottom)
				(hide yes)
			)
		)
		(property "Datasheet" "https://www.bourns.com/docs/product-datasheets/cr.pdf"
			(at 350.52 12.7 0)
			(effects
				(font
					(size 1.27 1.27)
					(thickness 0.15)
				)
				(justify left bottom)
				(hide yes)
			)
		)
		(property "Description" "SMD Chip Resistor"
			(at 363.22 12.7 0)
			(effects
				(font
					(size 1.27 1.27)
				)
				(justify left bottom)
				(hide yes)
			)
		)
		(property "MPN" "CR0402-FX-9092GLF"
			(at 353.06 12.7 0)
			(effects
				(font
					(size 1.27 1.27)
					(thickness 0.15)
				)
				(justify left bottom)
				(hide yes)
			)
		)
		(property "Manufacturer" "Bourns"
			(at 355.6 12.7 0)
			(effects
				(font
					(size 1.27 1.27)
					(thickness 0.15)
				)
				(justify left bottom)
				(hide yes)
			)
		)
		(property "License" "Apache-2.0"
			(at 358.14 12.7 0)
			(effects
				(font
					(size 1.27 1.27)
					(thickness 0.15)
				)
				(justify left bottom)
				(hide yes)
			)
		)
		(property "Author" "Antmicro"
			(at 360.68 12.7 0)
			(effects
				(font
					(size 1.27 1.27)
					(thickness 0.15)
				)
				(justify left bottom)
				(hide yes)
			)
		)
		(property "Val" "90k9"
			(at 334.01 31.75 90)
			(effects
				(font
					(size 1.27 1.27)
					(thickness 0.15)
				)
				(justify right)
			)
		)
		(property "Tolerance" "1%"
			(at 342.9 12.7 0)
			(effects
				(font
					(size 1.27 1.27)
				)
				(justify left bottom)
				(hide yes)
			)
		)
		(pin "2"
		)
		(pin "1"
		)
		(instances
			(project "oculink-to-10gbe-adapter"
				(path ""
					(reference "R3")
					(unit 1)
				)
			)
		)
	)
	(symbol
		(lib_id "antmicroResistors0603:R_0R_22.4A_0603")
		(at 379.73 101.6 0)
		(unit 1)
		(exclude_from_sim no)
		(in_bom yes)
		(on_board yes)
		(dnp no)
		(property "Reference" "R14"
			(at 379.73 100.33 0)
			(effects
				(font
					(size 1.27 1.27)
					(thickness 0.15)
				)
				(justify right)
			)
		)
		(property "Value" "R_0R_22.4A_0603"
			(at 394.97 106.68 0)
			(effects
				(font
					(size 1.27 1.27)
					(thickness 0.15)
				)
				(justify left bottom)
				(hide yes)
			)
		)
		(property "Footprint" "antmicro-footprints:R_0603_1608Metric"
			(at 394.97 111.76 0)
			(effects
				(font
					(size 1.27 1.27)
					(thickness 0.15)
				)
				(justify left bottom)
				(hide yes)
			)
		)
		(property "Datasheet" "https://fscdn.rohm.com/en/products/databook/datasheet/passive/resistor/chip_resistor/pmr-jpw-e.pdf"
			(at 394.97 114.3 0)
			(effects
				(font
					(size 1.27 1.27)
					(thickness 0.15)
				)
				(justify left bottom)
				(hide yes)
			)
		)
		(property "Description" "SMD Chip Resistor"
			(at 394.97 129.54 0)
			(effects
				(font
					(size 1.27 1.27)
				)
				(justify left bottom)
				(hide yes)
			)
		)
		(property "MPN" "PMR03EZPJ000"
			(at 394.97 116.84 0)
			(effects
				(font
					(size 1.27 1.27)
					(thickness 0.15)
				)
				(justify left bottom)
				(hide yes)
			)
		)
		(property "Manufacturer" "ROHM Semiconductor"
			(at 394.97 119.38 0)
			(effects
				(font
					(size 1.27 1.27)
					(thickness 0.15)
				)
				(justify left bottom)
				(hide yes)
			)
		)
		(property "Val" "0R"
			(at 384.81 100.33 0)
			(effects
				(font
					(size 1.27 1.27)
					(thickness 0.15)
				)
				(justify left)
			)
		)
		(property "Max. Curr." "22.4A"
			(at 382.27 104.14 0)
			(effects
				(font
					(size 1.27 1.27)
					(thickness 0.15)
				)
			)
		)
		(property "Author" "Antmicro"
			(at 394.97 124.46 0)
			(effects
				(font
					(size 1.27 1.27)
					(thickness 0.15)
				)
				(justify left bottom)
				(hide yes)
			)
		)
		(property "License" "Apache-2.0"
			(at 394.97 127 0)
			(effects
				(font
					(size 1.27 1.27)
					(thickness 0.15)
				)
				(justify left bottom)
				(hide yes)
			)
		)
		(property "Tolerance" "template_tolerance"
			(at 400.05 111.76 0)
			(effects
				(font
					(size 1.27 1.27)
				)
				(justify left bottom)
				(hide yes)
			)
		)
		(pin "1"
		)
		(pin "2"
		)
		(instances
			(project "OCuLink to 10GbE adapter"
				(path ""
					(reference "R14")
					(unit 1)
				)
			)
		)
	)
	(symbol
		(lib_id "antmicropower:+3V3")
		(at 387.35 228.6 90)
		(unit 1)
		(exclude_from_sim no)
		(in_bom yes)
		(on_board yes)
		(dnp no)
		(fields_autoplaced yes)
		(property "Reference" "#PWR0305"
			(at 387.35 213.36 0)
			(effects
				(font
					(size 1.27 1.27)
					(thickness 0.15)
				)
				(justify left bottom)
				(hide yes)
			)
		)
		(property "Value" "+3V3"
			(at 383.54 228.6 90)
			(effects
				(font
					(size 1.27 1.27)
					(thickness 0.15)
				)
				(justify left)
			)
		)
		(property "Footprint" ""
			(at 394.97 213.36 0)
			(effects
				(font
					(size 1.27 1.27)
					(thickness 0.15)
				)
				(justify left bottom)
				(hide yes)
			)
		)
		(property "Datasheet" ""
			(at 397.51 213.36 0)
			(effects
				(font
					(size 1.27 1.27)
					(thickness 0.15)
				)
				(justify left bottom)
				(hide yes)
			)
		)
		(property "Description" ""
			(at 387.35 228.6 0)
			(effects
				(font
					(size 1.27 1.27)
				)
				(hide yes)
			)
		)
		(property "Author" "Antmicro"
			(at 389.89 213.36 0)
			(effects
				(font
					(size 1.27 1.27)
					(thickness 0.15)
				)
				(justify left bottom)
				(hide yes)
			)
		)
		(property "License" "Apache-2.0"
			(at 392.43 213.36 0)
			(effects
				(font
					(size 1.27 1.27)
					(thickness 0.15)
				)
				(justify left bottom)
				(hide yes)
			)
		)
		(pin "1"
		)
		(instances
			(project "oculink-to-10gbe-adapter"
				(path ""
					(reference "#PWR0305")
					(unit 1)
				)
			)
		)
	)
	(symbol
		(lib_id "antmicroCapacitors0603:C_22u_16V_0603")
		(at 354.33 152.4 90)
		(unit 1)
		(exclude_from_sim no)
		(in_bom yes)
		(on_board yes)
		(dnp no)
		(property "Reference" "C35"
			(at 356.108 148.59 90)
			(effects
				(font
					(size 1.27 1.27)
					(thickness 0.15)
				)
				(justify right)
			)
		)
		(property "Value" "C_22u_16V_0603"
			(at 364.49 132.08 0)
			(effects
				(font
					(size 1.27 1.27)
					(thickness 0.15)
				)
				(justify left bottom)
				(hide yes)
			)
		)
		(property "Footprint" "antmicro-footprints:C_0603_1608Metric_EIA"
			(at 367.03 132.08 0)
			(effects
				(font
					(size 1.27 1.27)
					(thickness 0.15)
				)
				(justify left bottom)
				(hide yes)
			)
		)
		(property "Datasheet" "https://product.samsungsem.com/mlcc/CL10A226MO7JZN.do"
			(at 369.57 132.08 0)
			(effects
				(font
					(size 1.27 1.27)
					(thickness 0.15)
				)
				(justify left bottom)
				(hide yes)
			)
		)
		(property "Description" "SMD Multilayer Ceramic Capacitor"
			(at 354.33 152.4 0)
			(effects
				(font
					(size 1.27 1.27)
				)
				(hide yes)
			)
		)
		(property "MPN" "CL10A226MO7JZNC"
			(at 372.11 132.08 0)
			(effects
				(font
					(size 1.27 1.27)
					(thickness 0.15)
				)
				(justify left bottom)
				(hide yes)
			)
		)
		(property "Manufacturer" "Samsung Electro-Mechanics"
			(at 374.65 132.08 0)
			(effects
				(font
					(size 1.27 1.27)
					(thickness 0.15)
				)
				(justify left bottom)
				(hide yes)
			)
		)
		(property "License" "Apache-2.0"
			(at 377.19 132.08 0)
			(effects
				(font
					(size 1.27 1.27)
					(thickness 0.15)
				)
				(justify left bottom)
				(hide yes)
			)
		)
		(property "Author" "Antmicro"
			(at 379.73 132.08 0)
			(effects
				(font
					(size 1.27 1.27)
					(thickness 0.15)
				)
				(justify left bottom)
				(hide yes)
			)
		)
		(property "Val" "22u"
			(at 356.108 151.13 90)
			(effects
				(font
					(size 1.27 1.27)
					(thickness 0.15)
				)
				(justify right)
			)
		)
		(property "Voltage" "16V"
			(at 356.87 152.3935 90)
			(effects
				(font
					(size 1.27 1.27)
				)
				(justify right)
				(hide yes)
			)
		)
		(property "Dielectric" ""
			(at 384.81 132.08 0)
			(effects
				(font
					(size 1.27 1.27)
				)
				(justify left bottom)
				(hide yes)
			)
		)
		(property "Public" "False"
			(at 387.35 132.08 0)
			(effects
				(font
					(size 1.27 1.27)
				)
				(justify left bottom)
				(hide yes)
			)
		)
		(pin "2"
		)
		(pin "1"
		)
		(instances
			(project "OCuLink to 10GbE adapter"
				(path ""
					(reference "C35")
					(unit 1)
				)
			)
		)
	)
	(symbol
		(lib_id "antmicroFixedInductors:L_2u2_5.8A_WE-PMFI-35329222")
		(at 314.96 25.4 0)
		(unit 1)
		(exclude_from_sim no)
		(in_bom yes)
		(on_board yes)
		(dnp no)
		(fields_autoplaced yes)
		(property "Reference" "L1"
			(at 317.5 20.32 0)
			(effects
				(font
					(size 1.27 1.27)
					(thickness 0.15)
				)
			)
		)
		(property "Value" "L_2u2_5.8A_WE-PMFI-35329222"
			(at 328.93 27.94 0)
			(effects
				(font
					(size 1.27 1.27)
					(thickness 0.15)
				)
				(justify left bottom)
				(hide yes)
			)
		)
		(property "Footprint" "antmicro-footprints:L_WE-PMFI-353220"
			(at 328.93 33.02 0)
			(effects
				(font
					(size 1.27 1.27)
					(thickness 0.15)
				)
				(justify left bottom)
				(hide yes)
			)
		)
		(property "Datasheet" "https://www.we-online.com/components/products/datasheet/74479335329222.pdf"
			(at 328.93 35.56 0)
			(effects
				(font
					(size 1.27 1.27)
					(thickness 0.15)
				)
				(justify left bottom)
				(hide yes)
			)
		)
		(property "Description" "Power Inductors - SMD WE-PMFI 2.2 uH 5.8 A 40 mOhms AEC-Q200"
			(at 328.93 55.88 0)
			(effects
				(font
					(size 1.27 1.27)
				)
				(justify left bottom)
				(hide yes)
			)
		)
		(property "Val" "2u2/5.8A"
			(at 317.5 22.86 0)
			(effects
				(font
					(size 1.27 1.27)
					(thickness 0.15)
				)
			)
		)
		(property "Manufacturer" "Würth Elektronik"
			(at 328.93 38.1 0)
			(effects
				(font
					(size 1.27 1.27)
					(thickness 0.15)
				)
				(justify left bottom)
				(hide yes)
			)
		)
		(property "MPN" "74479335329222"
			(at 328.93 40.64 0)
			(effects
				(font
					(size 1.27 1.27)
					(thickness 0.15)
				)
				(justify left bottom)
				(hide yes)
			)
		)
		(property "ISat" "7.8A"
			(at 328.93 43.18 0)
			(effects
				(font
					(size 1.27 1.27)
				)
				(justify left bottom)
				(hide yes)
			)
		)
		(property "IMax" "5.8A"
			(at 328.93 45.72 0)
			(effects
				(font
					(size 1.27 1.27)
					(thickness 0.15)
				)
				(justify left bottom)
				(hide yes)
			)
		)
		(property "Size" "3.5x3.2x2.0"
			(at 328.93 48.26 0)
			(effects
				(font
					(size 1.27 1.27)
					(thickness 0.15)
				)
				(justify left bottom)
				(hide yes)
			)
		)
		(property "Author" "Antmicro"
			(at 328.93 50.8 0)
			(effects
				(font
					(size 1.27 1.27)
					(thickness 0.15)
				)
				(justify left bottom)
				(hide yes)
			)
		)
		(property "License" "Apache-2.0"
			(at 328.93 53.34 0)
			(effects
				(font
					(size 1.27 1.27)
					(thickness 0.15)
				)
				(justify left bottom)
				(hide yes)
			)
		)
		(pin "1"
		)
		(pin "2"
		)
		(instances
			(project ""
				(path ""
					(reference "L1")
					(unit 1)
				)
			)
		)
	)
	(symbol
		(lib_id "antmicroCapacitors0603:C_22u_16V_0603")
		(at 217.17 152.4 270)
		(mirror x)
		(unit 1)
		(exclude_from_sim no)
		(in_bom yes)
		(on_board yes)
		(dnp no)
		(property "Reference" "C30"
			(at 215.138 148.59 90)
			(effects
				(font
					(size 1.27 1.27)
					(thickness 0.15)
				)
				(justify right)
			)
		)
		(property "Value" "C_22u_16V_0603"
			(at 207.01 132.08 0)
			(effects
				(font
					(size 1.27 1.27)
					(thickness 0.15)
				)
				(justify left bottom)
				(hide yes)
			)
		)
		(property "Footprint" "antmicro-footprints:C_0603_1608Metric_EIA"
			(at 204.47 132.08 0)
			(effects
				(font
					(size 1.27 1.27)
					(thickness 0.15)
				)
				(justify left bottom)
				(hide yes)
			)
		)
		(property "Datasheet" "https://product.samsungsem.com/mlcc/CL10A226MO7JZN.do"
			(at 201.93 132.08 0)
			(effects
				(font
					(size 1.27 1.27)
					(thickness 0.15)
				)
				(justify left bottom)
				(hide yes)
			)
		)
		(property "Description" "SMD Multilayer Ceramic Capacitor"
			(at 217.17 152.4 0)
			(effects
				(font
					(size 1.27 1.27)
				)
				(hide yes)
			)
		)
		(property "MPN" "CL10A226MO7JZNC"
			(at 199.39 132.08 0)
			(effects
				(font
					(size 1.27 1.27)
					(thickness 0.15)
				)
				(justify left bottom)
				(hide yes)
			)
		)
		(property "Manufacturer" "Samsung Electro-Mechanics"
			(at 196.85 132.08 0)
			(effects
				(font
					(size 1.27 1.27)
					(thickness 0.15)
				)
				(justify left bottom)
				(hide yes)
			)
		)
		(property "License" "Apache-2.0"
			(at 194.31 132.08 0)
			(effects
				(font
					(size 1.27 1.27)
					(thickness 0.15)
				)
				(justify left bottom)
				(hide yes)
			)
		)
		(property "Author" "Antmicro"
			(at 191.77 132.08 0)
			(effects
				(font
					(size 1.27 1.27)
					(thickness 0.15)
				)
				(justify left bottom)
				(hide yes)
			)
		)
		(property "Val" "22u"
			(at 215.138 151.13 90)
			(effects
				(font
					(size 1.27 1.27)
					(thickness 0.15)
				)
				(justify right)
			)
		)
		(property "Voltage" "16V"
			(at 214.63 152.3935 90)
			(effects
				(font
					(size 1.27 1.27)
				)
				(justify right)
				(hide yes)
			)
		)
		(property "Dielectric" ""
			(at 186.69 132.08 0)
			(effects
				(font
					(size 1.27 1.27)
				)
				(justify left bottom)
				(hide yes)
			)
		)
		(property "Public" "False"
			(at 184.15 132.08 0)
			(effects
				(font
					(size 1.27 1.27)
				)
				(justify left bottom)
				(hide yes)
			)
		)
		(pin "2"
		)
		(pin "1"
		)
		(instances
			(project "OCuLink to 10GbE adapter"
				(path ""
					(reference "C30")
					(unit 1)
				)
			)
		)
	)
	(symbol
		(lib_id "antmicropower:GND")
		(at 217.17 195.58 0)
		(unit 1)
		(exclude_from_sim no)
		(in_bom yes)
		(on_board yes)
		(dnp no)
		(property "Reference" "#PWR053"
			(at 226.06 198.12 0)
			(effects
				(font
					(size 1.27 1.27)
					(thickness 0.15)
				)
				(justify left bottom)
				(hide yes)
			)
		)
		(property "Value" "GND"
			(at 217.17 199.39 0)
			(effects
				(font
					(size 1.27 1.27)
					(thickness 0.15)
				)
			)
		)
		(property "Footprint" ""
			(at 226.06 203.2 0)
			(effects
				(font
					(size 1.27 1.27)
					(thickness 0.15)
				)
				(justify left bottom)
				(hide yes)
			)
		)
		(property "Datasheet" ""
			(at 226.06 208.28 0)
			(effects
				(font
					(size 1.27 1.27)
					(thickness 0.15)
				)
				(justify left bottom)
				(hide yes)
			)
		)
		(property "Description" ""
			(at 217.17 195.58 0)
			(effects
				(font
					(size 1.27 1.27)
				)
				(hide yes)
			)
		)
		(property "Author" "Antmicro"
			(at 226.06 203.2 0)
			(effects
				(font
					(size 1.27 1.27)
					(thickness 0.15)
				)
				(justify left bottom)
				(hide yes)
			)
		)
		(property "License" "Apache-2.0"
			(at 226.06 205.74 0)
			(effects
				(font
					(size 1.27 1.27)
					(thickness 0.15)
				)
				(justify left bottom)
				(hide yes)
			)
		)
		(pin "1"
		)
		(instances
			(project "OCuLink to 10GbE adapter"
				(path ""
					(reference "#PWR053")
					(unit 1)
				)
			)
		)
	)
	(symbol
		(lib_id "antmicroResistors0402:R_30k_0402")
		(at 332.74 118.11 90)
		(unit 1)
		(exclude_from_sim no)
		(in_bom yes)
		(on_board yes)
		(dnp no)
		(property "Reference" "R18"
			(at 334.01 114.3 90)
			(effects
				(font
					(size 1.27 1.27)
					(thickness 0.15)
				)
				(justify right)
			)
		)
		(property "Value" "R_30k_0402"
			(at 345.44 97.79 0)
			(effects
				(font
					(size 1.27 1.27)
					(thickness 0.15)
				)
				(justify left bottom)
				(hide yes)
			)
		)
		(property "Footprint" "antmicro-footprints:R_0402_1005Metric"
			(at 347.98 97.79 0)
			(effects
				(font
					(size 1.27 1.27)
					(thickness 0.15)
				)
				(justify left bottom)
				(hide yes)
			)
		)
		(property "Datasheet" "https://www.bourns.com/docs/product-datasheets/cr.pdf"
			(at 350.52 97.79 0)
			(effects
				(font
					(size 1.27 1.27)
					(thickness 0.15)
				)
				(justify left bottom)
				(hide yes)
			)
		)
		(property "Description" "SMD Chip Resistor, 30 kohm, ± 1%, 63 mW, 0402 [1005 Metric], Thick Film, General Purpose"
			(at 363.22 97.79 0)
			(effects
				(font
					(size 1.27 1.27)
				)
				(justify left bottom)
				(hide yes)
			)
		)
		(property "MPN" "CR0402-FX-3002GLF"
			(at 353.06 97.79 0)
			(effects
				(font
					(size 1.27 1.27)
					(thickness 0.15)
				)
				(justify left bottom)
				(hide yes)
			)
		)
		(property "Manufacturer" "Bourns"
			(at 355.6 97.79 0)
			(effects
				(font
					(size 1.27 1.27)
					(thickness 0.15)
				)
				(justify left bottom)
				(hide yes)
			)
		)
		(property "License" "Apache-2.0"
			(at 358.14 97.79 0)
			(effects
				(font
					(size 1.27 1.27)
					(thickness 0.15)
				)
				(justify left bottom)
				(hide yes)
			)
		)
		(property "Author" "Antmicro"
			(at 360.68 97.79 0)
			(effects
				(font
					(size 1.27 1.27)
					(thickness 0.15)
				)
				(justify left bottom)
				(hide yes)
			)
		)
		(property "Val" "30k"
			(at 334.01 116.84 90)
			(effects
				(font
					(size 1.27 1.27)
					(thickness 0.15)
				)
				(justify right)
			)
		)
		(property "Tolerance" "1%"
			(at 342.9 97.79 0)
			(effects
				(font
					(size 1.27 1.27)
				)
				(justify left bottom)
				(hide yes)
			)
		)
		(pin "2"
		)
		(pin "1"
		)
		(instances
			(project "OCuLink to 10GbE adapter"
				(path ""
					(reference "R18")
					(unit 1)
				)
			)
		)
	)
	(symbol
		(lib_id "antmicroDCDCConverters:TPS566231P")
		(at 276.86 63.5 0)
		(unit 1)
		(exclude_from_sim no)
		(in_bom yes)
		(on_board yes)
		(dnp no)
		(fields_autoplaced yes)
		(property "Reference" "U2"
			(at 285.75 57.15 0)
			(effects
				(font
					(size 1.27 1.27)
					(thickness 0.15)
				)
			)
		)
		(property "Value" "TPS566231P"
			(at 309.88 68.58 0)
			(effects
				(font
					(size 1.27 1.27)
					(thickness 0.15)
				)
				(justify left bottom)
				(hide yes)
			)
		)
		(property "Footprint" "antmicro-footprints:VQFN-HR-9_2x1.5mm"
			(at 309.88 71.12 0)
			(effects
				(font
					(size 1.27 1.27)
					(thickness 0.15)
				)
				(justify left bottom)
				(hide yes)
			)
		)
		(property "Datasheet" "https://www.ti.com/lit/ds/symlink/tps566231.pdf"
			(at 309.88 73.66 0)
			(effects
				(font
					(size 1.27 1.27)
					(thickness 0.15)
				)
				(justify left bottom)
				(hide yes)
			)
		)
		(property "Description" "Switching Voltage Regulators 3-V to 18-V, 6-A synchronous buck converter"
			(at 309.88 86.36 0)
			(effects
				(font
					(size 1.27 1.27)
				)
				(justify left bottom)
				(hide yes)
			)
		)
		(property "Manufacturer" "Texas Instruments"
			(at 309.88 76.2 0)
			(effects
				(font
					(size 1.27 1.27)
					(thickness 0.15)
				)
				(justify left bottom)
				(hide yes)
			)
		)
		(property "MPN" "TPS566231PRQFR"
			(at 285.75 59.69 0)
			(effects
				(font
					(size 1.27 1.27)
					(thickness 0.15)
				)
			)
		)
		(property "Author" "Antmicro"
			(at 309.88 81.28 0)
			(effects
				(font
					(size 1.27 1.27)
					(thickness 0.15)
				)
				(justify left bottom)
				(hide yes)
			)
		)
		(property "License" "Apache-2.0"
			(at 309.88 83.82 0)
			(effects
				(font
					(size 1.27 1.27)
					(thickness 0.15)
				)
				(justify left bottom)
				(hide yes)
			)
		)
		(pin "1"
		)
		(pin "2"
		)
		(pin "3"
		)
		(pin "9"
		)
		(pin "5"
		)
		(pin "6"
		)
		(pin "8"
		)
		(pin "4"
		)
		(pin "7"
		)
		(instances
			(project "OCuLink to 10GbE adapter"
				(path ""
					(reference "U2")
					(unit 1)
				)
			)
		)
	)
	(symbol
		(lib_id "antmicropower:GND")
		(at 354.33 43.18 0)
		(unit 1)
		(exclude_from_sim no)
		(in_bom yes)
		(on_board yes)
		(dnp no)
		(property "Reference" "#PWR011"
			(at 363.22 45.72 0)
			(effects
				(font
					(size 1.27 1.27)
					(thickness 0.15)
				)
				(justify left bottom)
				(hide yes)
			)
		)
		(property "Value" "GND"
			(at 354.33 46.99 0)
			(effects
				(font
					(size 1.27 1.27)
					(thickness 0.15)
				)
			)
		)
		(property "Footprint" ""
			(at 363.22 50.8 0)
			(effects
				(font
					(size 1.27 1.27)
					(thickness 0.15)
				)
				(justify left bottom)
				(hide yes)
			)
		)
		(property "Datasheet" ""
			(at 363.22 55.88 0)
			(effects
				(font
					(size 1.27 1.27)
					(thickness 0.15)
				)
				(justify left bottom)
				(hide yes)
			)
		)
		(property "Description" ""
			(at 354.33 43.18 0)
			(effects
				(font
					(size 1.27 1.27)
				)
				(hide yes)
			)
		)
		(property "Author" "Antmicro"
			(at 363.22 50.8 0)
			(effects
				(font
					(size 1.27 1.27)
					(thickness 0.15)
				)
				(justify left bottom)
				(hide yes)
			)
		)
		(property "License" "Apache-2.0"
			(at 363.22 53.34 0)
			(effects
				(font
					(size 1.27 1.27)
					(thickness 0.15)
				)
				(justify left bottom)
				(hide yes)
			)
		)
		(pin "1"
		)
		(instances
			(project "OCuLink to 10GbE adapter"
				(path ""
					(reference "#PWR011")
					(unit 1)
				)
			)
		)
	)
	(symbol
		(lib_id "antmicropower:GND")
		(at 44.45 102.87 0)
		(unit 1)
		(exclude_from_sim no)
		(in_bom yes)
		(on_board yes)
		(dnp no)
		(property "Reference" "#PWR024"
			(at 53.34 105.41 0)
			(effects
				(font
					(size 1.27 1.27)
					(thickness 0.15)
				)
				(justify left bottom)
				(hide yes)
			)
		)
		(property "Value" "GND"
			(at 44.45 106.68 0)
			(effects
				(font
					(size 1.27 1.27)
					(thickness 0.15)
				)
			)
		)
		(property "Footprint" ""
			(at 53.34 110.49 0)
			(effects
				(font
					(size 1.27 1.27)
					(thickness 0.15)
				)
				(justify left bottom)
				(hide yes)
			)
		)
		(property "Datasheet" ""
			(at 53.34 115.57 0)
			(effects
				(font
					(size 1.27 1.27)
					(thickness 0.15)
				)
				(justify left bottom)
				(hide yes)
			)
		)
		(property "Description" ""
			(at 44.45 102.87 0)
			(effects
				(font
					(size 1.27 1.27)
				)
				(hide yes)
			)
		)
		(property "Author" "Antmicro"
			(at 53.34 110.49 0)
			(effects
				(font
					(size 1.27 1.27)
					(thickness 0.15)
				)
				(justify left bottom)
				(hide yes)
			)
		)
		(property "License" "Apache-2.0"
			(at 53.34 113.03 0)
			(effects
				(font
					(size 1.27 1.27)
					(thickness 0.15)
				)
				(justify left bottom)
				(hide yes)
			)
		)
		(pin "1"
		)
		(instances
			(project "OCuLink to 10GbE adapter"
				(path ""
					(reference "#PWR024")
					(unit 1)
				)
			)
		)
	)
	(symbol
		(lib_id "antmicroResistors0402:R_1k_0402")
		(at 254 231.14 90)
		(unit 1)
		(exclude_from_sim no)
		(in_bom yes)
		(on_board yes)
		(dnp no)
		(property "Reference" "R147"
			(at 255.27 227.33 90)
			(effects
				(font
					(size 1.27 1.27)
					(thickness 0.15)
				)
				(justify right)
			)
		)
		(property "Value" "R_1k_0402"
			(at 266.7 210.82 0)
			(effects
				(font
					(size 1.27 1.27)
					(thickness 0.15)
				)
				(justify left bottom)
				(hide yes)
			)
		)
		(property "Footprint" "antmicro-footprints:R_0402_1005Metric"
			(at 269.24 210.82 0)
			(effects
				(font
					(size 1.27 1.27)
					(thickness 0.15)
				)
				(justify left bottom)
				(hide yes)
			)
		)
		(property "Datasheet" "https://www.bourns.com/docs/product-datasheets/cr.pdf"
			(at 271.78 210.82 0)
			(effects
				(font
					(size 1.27 1.27)
					(thickness 0.15)
				)
				(justify left bottom)
				(hide yes)
			)
		)
		(property "Description" "SMD Chip Resistor, 1 kohm, ± 1%, 63 mW, 0402 [1005 Metric], Thick Film, General Purpose"
			(at 284.48 210.82 0)
			(effects
				(font
					(size 1.27 1.27)
				)
				(justify left bottom)
				(hide yes)
			)
		)
		(property "MPN" "CR0402-FX-1001GLF"
			(at 274.32 210.82 0)
			(effects
				(font
					(size 1.27 1.27)
					(thickness 0.15)
				)
				(justify left bottom)
				(hide yes)
			)
		)
		(property "Manufacturer" "Bourns"
			(at 276.86 210.82 0)
			(effects
				(font
					(size 1.27 1.27)
					(thickness 0.15)
				)
				(justify left bottom)
				(hide yes)
			)
		)
		(property "License" "Apache-2.0"
			(at 279.4 210.82 0)
			(effects
				(font
					(size 1.27 1.27)
					(thickness 0.15)
				)
				(justify left bottom)
				(hide yes)
			)
		)
		(property "Author" "Antmicro"
			(at 281.94 210.82 0)
			(effects
				(font
					(size 1.27 1.27)
					(thickness 0.15)
				)
				(justify left bottom)
				(hide yes)
			)
		)
		(property "Val" "1k"
			(at 255.27 229.87 90)
			(effects
				(font
					(size 1.27 1.27)
					(thickness 0.15)
				)
				(justify right)
			)
		)
		(property "Tolerance" "1%"
			(at 264.16 210.82 0)
			(effects
				(font
					(size 1.27 1.27)
				)
				(justify left bottom)
				(hide yes)
			)
		)
		(pin "1"
		)
		(pin "2"
		)
		(instances
			(project "oculink-to-10gbe-adapter"
				(path ""
					(reference "R147")
					(unit 1)
				)
			)
		)
	)
	(symbol
		(lib_id "antmicroCapacitors0402:C_100n_0402")
		(at 307.34 144.78 270)
		(mirror x)
		(unit 1)
		(exclude_from_sim no)
		(in_bom yes)
		(on_board yes)
		(dnp no)
		(property "Reference" "C28"
			(at 309.118 141.224 90)
			(effects
				(font
					(size 1.27 1.27)
					(thickness 0.15)
				)
				(justify left)
			)
		)
		(property "Value" "C_100n_0402"
			(at 297.18 124.46 0)
			(effects
				(font
					(size 1.27 1.27)
					(thickness 0.15)
				)
				(justify left bottom)
				(hide yes)
			)
		)
		(property "Footprint" "antmicro-footprints:C_0402_1005Metric"
			(at 294.64 124.46 0)
			(effects
				(font
					(size 1.27 1.27)
					(thickness 0.15)
				)
				(justify left bottom)
				(hide yes)
			)
		)
		(property "Datasheet" "https://www.murata.com/products/productdetail?partno=GRM155R61H104KE14%23"
			(at 292.1 124.46 0)
			(effects
				(font
					(size 1.27 1.27)
					(thickness 0.15)
				)
				(justify left bottom)
				(hide yes)
			)
		)
		(property "Description" "SMD Multilayer Ceramic Capacitor, 0.1 µF, 50 V, 0402 [1005 Metric], ± 10%, X5R, GRM Series"
			(at 274.32 124.46 0)
			(effects
				(font
					(size 1.27 1.27)
				)
				(justify left bottom)
				(hide yes)
			)
		)
		(property "MPN" "GRM155R61H104KE14D"
			(at 289.56 124.46 0)
			(effects
				(font
					(size 1.27 1.27)
					(thickness 0.15)
				)
				(justify left bottom)
				(hide yes)
			)
		)
		(property "Manufacturer" "Murata"
			(at 287.02 124.46 0)
			(effects
				(font
					(size 1.27 1.27)
					(thickness 0.15)
				)
				(justify left bottom)
				(hide yes)
			)
		)
		(property "License" "Apache-2.0"
			(at 284.48 124.46 0)
			(effects
				(font
					(size 1.27 1.27)
					(thickness 0.15)
				)
				(justify left bottom)
				(hide yes)
			)
		)
		(property "Author" "Antmicro"
			(at 281.94 124.46 0)
			(effects
				(font
					(size 1.27 1.27)
					(thickness 0.15)
				)
				(justify left bottom)
				(hide yes)
			)
		)
		(property "Val" "100n"
			(at 309.118 143.764 90)
			(effects
				(font
					(size 1.27 1.27)
					(thickness 0.15)
				)
				(justify left)
			)
		)
		(property "Voltage" "50V"
			(at 279.4 124.46 0)
			(effects
				(font
					(size 1.27 1.27)
				)
				(justify left bottom)
				(hide yes)
			)
		)
		(property "Dielectric" "X5R"
			(at 276.86 124.46 0)
			(effects
				(font
					(size 1.27 1.27)
				)
				(justify left bottom)
				(hide yes)
			)
		)
		(pin "1"
		)
		(pin "2"
		)
		(instances
			(project "OCuLink to 10GbE adapter"
				(path ""
					(reference "C28")
					(unit 1)
				)
			)
		)
	)
	(symbol
		(lib_id "antmicroResistors0402:R_1k_0402")
		(at 91.44 147.32 90)
		(unit 1)
		(exclude_from_sim no)
		(in_bom yes)
		(on_board yes)
		(dnp no)
		(property "Reference" "R20"
			(at 92.71 143.51 90)
			(effects
				(font
					(size 1.27 1.27)
					(thickness 0.15)
				)
				(justify right)
			)
		)
		(property "Value" "R_1k_0402"
			(at 104.14 127 0)
			(effects
				(font
					(size 1.27 1.27)
					(thickness 0.15)
				)
				(justify left bottom)
				(hide yes)
			)
		)
		(property "Footprint" "antmicro-footprints:R_0402_1005Metric"
			(at 106.68 127 0)
			(effects
				(font
					(size 1.27 1.27)
					(thickness 0.15)
				)
				(justify left bottom)
				(hide yes)
			)
		)
		(property "Datasheet" "https://www.bourns.com/docs/product-datasheets/cr.pdf"
			(at 109.22 127 0)
			(effects
				(font
					(size 1.27 1.27)
					(thickness 0.15)
				)
				(justify left bottom)
				(hide yes)
			)
		)
		(property "Description" "SMD Chip Resistor, 1 kohm, ± 1%, 63 mW, 0402 [1005 Metric], Thick Film, General Purpose"
			(at 121.92 127 0)
			(effects
				(font
					(size 1.27 1.27)
				)
				(justify left bottom)
				(hide yes)
			)
		)
		(property "MPN" "CR0402-FX-1001GLF"
			(at 111.76 127 0)
			(effects
				(font
					(size 1.27 1.27)
					(thickness 0.15)
				)
				(justify left bottom)
				(hide yes)
			)
		)
		(property "Manufacturer" "Bourns"
			(at 114.3 127 0)
			(effects
				(font
					(size 1.27 1.27)
					(thickness 0.15)
				)
				(justify left bottom)
				(hide yes)
			)
		)
		(property "License" "Apache-2.0"
			(at 116.84 127 0)
			(effects
				(font
					(size 1.27 1.27)
					(thickness 0.15)
				)
				(justify left bottom)
				(hide yes)
			)
		)
		(property "Author" "Antmicro"
			(at 119.38 127 0)
			(effects
				(font
					(size 1.27 1.27)
					(thickness 0.15)
				)
				(justify left bottom)
				(hide yes)
			)
		)
		(property "Val" "1k"
			(at 92.71 146.05 90)
			(effects
				(font
					(size 1.27 1.27)
					(thickness 0.15)
				)
				(justify right)
			)
		)
		(property "Tolerance" "1%"
			(at 101.6 127 0)
			(effects
				(font
					(size 1.27 1.27)
				)
				(justify left bottom)
				(hide yes)
			)
		)
		(pin "1"
		)
		(pin "2"
		)
		(instances
			(project "oculink-to-10gbe-adapter"
				(path ""
					(reference "R20")
					(unit 1)
				)
			)
		)
	)
	(symbol
		(lib_id "antmicroCapacitors0603:C_22u_16V_0603")
		(at 227.33 114.3 270)
		(mirror x)
		(unit 1)
		(exclude_from_sim no)
		(in_bom yes)
		(on_board yes)
		(dnp no)
		(property "Reference" "C22"
			(at 225.552 110.49 90)
			(effects
				(font
					(size 1.27 1.27)
					(thickness 0.15)
				)
				(justify right)
			)
		)
		(property "Value" "C_22u_16V_0603"
			(at 217.17 93.98 0)
			(effects
				(font
					(size 1.27 1.27)
					(thickness 0.15)
				)
				(justify left bottom)
				(hide yes)
			)
		)
		(property "Footprint" "antmicro-footprints:C_0603_1608Metric_EIA"
			(at 214.63 93.98 0)
			(effects
				(font
					(size 1.27 1.27)
					(thickness 0.15)
				)
				(justify left bottom)
				(hide yes)
			)
		)
		(property "Datasheet" "https://product.samsungsem.com/mlcc/CL10A226MO7JZN.do"
			(at 212.09 93.98 0)
			(effects
				(font
					(size 1.27 1.27)
					(thickness 0.15)
				)
				(justify left bottom)
				(hide yes)
			)
		)
		(property "Description" "SMD Multilayer Ceramic Capacitor"
			(at 227.33 114.3 0)
			(effects
				(font
					(size 1.27 1.27)
				)
				(hide yes)
			)
		)
		(property "MPN" "CL10A226MO7JZNC"
			(at 209.55 93.98 0)
			(effects
				(font
					(size 1.27 1.27)
					(thickness 0.15)
				)
				(justify left bottom)
				(hide yes)
			)
		)
		(property "Manufacturer" "Samsung Electro-Mechanics"
			(at 207.01 93.98 0)
			(effects
				(font
					(size 1.27 1.27)
					(thickness 0.15)
				)
				(justify left bottom)
				(hide yes)
			)
		)
		(property "License" "Apache-2.0"
			(at 204.47 93.98 0)
			(effects
				(font
					(size 1.27 1.27)
					(thickness 0.15)
				)
				(justify left bottom)
				(hide yes)
			)
		)
		(property "Author" "Antmicro"
			(at 201.93 93.98 0)
			(effects
				(font
					(size 1.27 1.27)
					(thickness 0.15)
				)
				(justify left bottom)
				(hide yes)
			)
		)
		(property "Val" "22u"
			(at 225.552 113.03 90)
			(effects
				(font
					(size 1.27 1.27)
					(thickness 0.15)
				)
				(justify right)
			)
		)
		(property "Voltage" "16V"
			(at 224.79 114.2935 90)
			(effects
				(font
					(size 1.27 1.27)
				)
				(justify right)
				(hide yes)
			)
		)
		(property "Dielectric" ""
			(at 196.85 93.98 0)
			(effects
				(font
					(size 1.27 1.27)
				)
				(justify left bottom)
				(hide yes)
			)
		)
		(property "Public" "False"
			(at 194.31 93.98 0)
			(effects
				(font
					(size 1.27 1.27)
				)
				(justify left bottom)
				(hide yes)
			)
		)
		(pin "2"
		)
		(pin "1"
		)
		(instances
			(project "OCuLink to 10GbE adapter"
				(path ""
					(reference "C22")
					(unit 1)
				)
			)
		)
	)
	(symbol
		(lib_id "antmicroTestPoints:TP_1mm_SMD")
		(at 391.16 236.22 0)
		(unit 1)
		(exclude_from_sim no)
		(in_bom no)
		(on_board yes)
		(dnp no)
		(fields_autoplaced yes)
		(property "Reference" "TP33"
			(at 396.24 236.22 0)
			(effects
				(font
					(size 1.27 1.27)
					(thickness 0.15)
				)
				(justify left)
			)
		)
		(property "Value" "TP_1mm_SMD"
			(at 406.4 243.84 0)
			(effects
				(font
					(size 1.27 1.27)
					(thickness 0.15)
				)
				(justify left bottom)
				(hide yes)
			)
		)
		(property "Footprint" "antmicro-footprints:TP_SMD_1mm"
			(at 406.4 246.38 0)
			(effects
				(font
					(size 1.27 1.27)
					(thickness 0.15)
				)
				(justify left bottom)
				(hide yes)
			)
		)
		(property "Datasheet" ""
			(at 408.94 248.92 0)
			(effects
				(font
					(size 1.27 1.27)
					(thickness 0.15)
				)
				(justify left bottom)
				(hide yes)
			)
		)
		(property "Description" "Test point 1mm SMD"
			(at 406.4 256.54 0)
			(effects
				(font
					(size 1.27 1.27)
				)
				(justify left bottom)
				(hide yes)
			)
		)
		(property "MPN" ""
			(at 391.16 236.22 0)
			(effects
				(font
					(size 1.27 1.27)
				)
				(hide yes)
			)
		)
		(property "Manufacturer" ""
			(at 391.16 236.22 0)
			(effects
				(font
					(size 1.27 1.27)
				)
				(hide yes)
			)
		)
		(property "Author" "Antmicro"
			(at 406.4 251.46 0)
			(effects
				(font
					(size 1.27 1.27)
					(thickness 0.15)
				)
				(justify left bottom)
				(hide yes)
			)
		)
		(property "License" "Apache-2.0"
			(at 406.4 254 0)
			(effects
				(font
					(size 1.27 1.27)
					(thickness 0.15)
				)
				(justify left bottom)
				(hide yes)
			)
		)
		(pin "1"
		)
		(instances
			(project "oculink-to-10gbe-adapter"
				(path ""
					(reference "TP33")
					(unit 1)
				)
			)
		)
	)
	(symbol
		(lib_id "antmicroResistors0402:R_0R_0402")
		(at 317.5 240.03 0)
		(unit 1)
		(exclude_from_sim no)
		(in_bom yes)
		(on_board yes)
		(dnp no)
		(property "Reference" "R33"
			(at 320.04 237.744 0)
			(effects
				(font
					(size 1.27 1.27)
					(thickness 0.15)
				)
			)
		)
		(property "Value" "R_0R_0402"
			(at 337.82 252.73 0)
			(effects
				(font
					(size 1.27 1.27)
					(thickness 0.15)
				)
				(justify left bottom)
				(hide yes)
			)
		)
		(property "Footprint" "antmicro-footprints:R_0402_1005Metric"
			(at 337.82 255.27 0)
			(effects
				(font
					(size 1.27 1.27)
					(thickness 0.15)
				)
				(justify left bottom)
				(hide yes)
			)
		)
		(property "Datasheet" "https://industrial.panasonic.com/cdbs/www-data/pdf/RDA0000/AOA0000C301.pdf"
			(at 337.82 257.81 0)
			(effects
				(font
					(size 1.27 1.27)
					(thickness 0.15)
				)
				(justify left bottom)
				(hide yes)
			)
		)
		(property "Description" "SMD Chip Resistor, Jumper, 0 ohm, 100 mW, 0402 [1005 Metric], Thick Film, General Purpose"
			(at 337.82 273.05 0)
			(effects
				(font
					(size 1.27 1.27)
				)
				(justify left bottom)
				(hide yes)
			)
		)
		(property "MPN" "ERJ2GE0R00X"
			(at 337.82 260.35 0)
			(effects
				(font
					(size 1.27 1.27)
					(thickness 0.15)
				)
				(justify left bottom)
				(hide yes)
			)
		)
		(property "Manufacturer" "Panasonic"
			(at 337.82 262.89 0)
			(effects
				(font
					(size 1.27 1.27)
					(thickness 0.15)
				)
				(justify left bottom)
				(hide yes)
			)
		)
		(property "License" "Apache-2.0"
			(at 337.82 265.43 0)
			(effects
				(font
					(size 1.27 1.27)
					(thickness 0.15)
				)
				(justify left bottom)
				(hide yes)
			)
		)
		(property "Author" "Antmicro"
			(at 337.82 267.97 0)
			(effects
				(font
					(size 1.27 1.27)
					(thickness 0.15)
				)
				(justify left bottom)
				(hide yes)
			)
		)
		(property "Val" "0R"
			(at 320.04 242.316 0)
			(effects
				(font
					(size 1.27 1.27)
					(thickness 0.15)
				)
			)
		)
		(property "Tolerance" "~"
			(at 337.82 250.19 0)
			(effects
				(font
					(size 1.27 1.27)
				)
				(justify left bottom)
				(hide yes)
			)
		)
		(property "Current" "1A"
			(at 337.82 270.51 0)
			(effects
				(font
					(size 1.27 1.27)
					(thickness 0.15)
				)
				(justify left bottom)
				(hide yes)
			)
		)
		(pin "2"
		)
		(pin "1"
		)
		(instances
			(project "OCuLink to 10GbE adapter"
				(path ""
					(reference "R33")
					(unit 1)
				)
			)
		)
	)
	(symbol
		(lib_id "antmicroCapacitors0603:C_22u_16V_0603")
		(at 354.33 190.5 90)
		(unit 1)
		(exclude_from_sim no)
		(in_bom yes)
		(on_board yes)
		(dnp no)
		(property "Reference" "C45"
			(at 356.108 186.69 90)
			(effects
				(font
					(size 1.27 1.27)
					(thickness 0.15)
				)
				(justify right)
			)
		)
		(property "Value" "C_22u_16V_0603"
			(at 364.49 170.18 0)
			(effects
				(font
					(size 1.27 1.27)
					(thickness 0.15)
				)
				(justify left bottom)
				(hide yes)
			)
		)
		(property "Footprint" "antmicro-footprints:C_0603_1608Metric_EIA"
			(at 367.03 170.18 0)
			(effects
				(font
					(size 1.27 1.27)
					(thickness 0.15)
				)
				(justify left bottom)
				(hide yes)
			)
		)
		(property "Datasheet" "https://product.samsungsem.com/mlcc/CL10A226MO7JZN.do"
			(at 369.57 170.18 0)
			(effects
				(font
					(size 1.27 1.27)
					(thickness 0.15)
				)
				(justify left bottom)
				(hide yes)
			)
		)
		(property "Description" "SMD Multilayer Ceramic Capacitor"
			(at 354.33 190.5 0)
			(effects
				(font
					(size 1.27 1.27)
				)
				(hide yes)
			)
		)
		(property "MPN" "CL10A226MO7JZNC"
			(at 372.11 170.18 0)
			(effects
				(font
					(size 1.27 1.27)
					(thickness 0.15)
				)
				(justify left bottom)
				(hide yes)
			)
		)
		(property "Manufacturer" "Samsung Electro-Mechanics"
			(at 374.65 170.18 0)
			(effects
				(font
					(size 1.27 1.27)
					(thickness 0.15)
				)
				(justify left bottom)
				(hide yes)
			)
		)
		(property "License" "Apache-2.0"
			(at 377.19 170.18 0)
			(effects
				(font
					(size 1.27 1.27)
					(thickness 0.15)
				)
				(justify left bottom)
				(hide yes)
			)
		)
		(property "Author" "Antmicro"
			(at 379.73 170.18 0)
			(effects
				(font
					(size 1.27 1.27)
					(thickness 0.15)
				)
				(justify left bottom)
				(hide yes)
			)
		)
		(property "Val" "22u"
			(at 356.108 189.23 90)
			(effects
				(font
					(size 1.27 1.27)
					(thickness 0.15)
				)
				(justify right)
			)
		)
		(property "Voltage" "16V"
			(at 356.87 190.4935 90)
			(effects
				(font
					(size 1.27 1.27)
				)
				(justify right)
				(hide yes)
			)
		)
		(property "Dielectric" ""
			(at 384.81 170.18 0)
			(effects
				(font
					(size 1.27 1.27)
				)
				(justify left bottom)
				(hide yes)
			)
		)
		(property "Public" "False"
			(at 387.35 170.18 0)
			(effects
				(font
					(size 1.27 1.27)
				)
				(justify left bottom)
				(hide yes)
			)
		)
		(pin "2"
		)
		(pin "1"
		)
		(instances
			(project "OCuLink to 10GbE adapter"
				(path ""
					(reference "C45")
					(unit 1)
				)
			)
		)
	)
	(symbol
		(lib_id "antmicroWire2BoardConnectors:Molex_Nano-Fit_1x2_SMD_1054301202")
		(at 41.91 85.09 0)
		(mirror y)
		(unit 1)
		(exclude_from_sim no)
		(in_bom yes)
		(on_board yes)
		(dnp no)
		(property "Reference" "J1"
			(at 34.29 86.36 0)
			(effects
				(font
					(size 1.27 1.27)
					(thickness 0.15)
				)
				(justify left)
			)
		)
		(property "Value" "Molex_Nano-Fit_1x2_SMD_1054301202"
			(at 15.24 92.71 0)
			(effects
				(font
					(size 1.27 1.27)
					(thickness 0.15)
				)
				(justify left bottom)
				(hide yes)
			)
		)
		(property "Footprint" "antmicro-footprints:Conn_Molex_Nano-Fit_1x2_SMD_1054301202"
			(at 15.24 95.25 0)
			(effects
				(font
					(size 1.27 1.27)
					(thickness 0.15)
				)
				(justify left bottom)
				(hide yes)
			)
		)
		(property "Datasheet" "https://www.farnell.com/cad/3578051.pdf"
			(at 15.24 97.79 0)
			(effects
				(font
					(size 1.27 1.27)
					(thickness 0.15)
				)
				(justify left bottom)
				(hide yes)
			)
		)
		(property "Description" "Pin Header, Pitch 2.5 mm, 1 Row, 2 Contacts, Nano-Fit"
			(at 41.91 85.09 0)
			(effects
				(font
					(size 1.27 1.27)
				)
				(hide yes)
			)
		)
		(property "Manufacturer" "Molex"
			(at 15.24 100.33 0)
			(effects
				(font
					(size 1.27 1.27)
					(thickness 0.15)
				)
				(justify left bottom)
				(hide yes)
			)
		)
		(property "MPN" "105430-1202"
			(at 34.29 88.9 0)
			(effects
				(font
					(size 1.27 1.27)
					(thickness 0.15)
				)
				(justify left)
			)
		)
		(property "Author" "Antmicro"
			(at 15.24 102.87 0)
			(effects
				(font
					(size 1.27 1.27)
					(thickness 0.15)
				)
				(justify left bottom)
				(hide yes)
			)
		)
		(property "License" "Apache-2.0"
			(at 15.24 105.41 0)
			(effects
				(font
					(size 1.27 1.27)
					(thickness 0.15)
				)
				(justify left bottom)
				(hide yes)
			)
		)
		(pin "MP"
		)
		(pin "2"
		)
		(pin "1"
		)
		(instances
			(project "OCuLink to 10GbE adapter"
				(path ""
					(reference "J1")
					(unit 1)
				)
			)
		)
	)
	(symbol
		(lib_id "antmicropower:GND")
		(at 237.49 81.28 0)
		(unit 1)
		(exclude_from_sim no)
		(in_bom yes)
		(on_board yes)
		(dnp no)
		(property "Reference" "#PWR016"
			(at 246.38 83.82 0)
			(effects
				(font
					(size 1.27 1.27)
					(thickness 0.15)
				)
				(justify left bottom)
				(hide yes)
			)
		)
		(property "Value" "GND"
			(at 237.49 85.09 0)
			(effects
				(font
					(size 1.27 1.27)
					(thickness 0.15)
				)
			)
		)
		(property "Footprint" ""
			(at 246.38 88.9 0)
			(effects
				(font
					(size 1.27 1.27)
					(thickness 0.15)
				)
				(justify left bottom)
				(hide yes)
			)
		)
		(property "Datasheet" ""
			(at 246.38 93.98 0)
			(effects
				(font
					(size 1.27 1.27)
					(thickness 0.15)
				)
				(justify left bottom)
				(hide yes)
			)
		)
		(property "Description" ""
			(at 237.49 81.28 0)
			(effects
				(font
					(size 1.27 1.27)
				)
				(hide yes)
			)
		)
		(property "Author" "Antmicro"
			(at 246.38 88.9 0)
			(effects
				(font
					(size 1.27 1.27)
					(thickness 0.15)
				)
				(justify left bottom)
				(hide yes)
			)
		)
		(property "License" "Apache-2.0"
			(at 246.38 91.44 0)
			(effects
				(font
					(size 1.27 1.27)
					(thickness 0.15)
				)
				(justify left bottom)
				(hide yes)
			)
		)
		(pin "1"
		)
		(instances
			(project "OCuLink to 10GbE adapter"
				(path ""
					(reference "#PWR016")
					(unit 1)
				)
			)
		)
	)
	(symbol
		(lib_id "antmicroCapacitors0603:C_22u_16V_0603")
		(at 217.17 114.3 270)
		(mirror x)
		(unit 1)
		(exclude_from_sim no)
		(in_bom yes)
		(on_board yes)
		(dnp no)
		(property "Reference" "C21"
			(at 215.138 110.49 90)
			(effects
				(font
					(size 1.27 1.27)
					(thickness 0.15)
				)
				(justify right)
			)
		)
		(property "Value" "C_22u_16V_0603"
			(at 207.01 93.98 0)
			(effects
				(font
					(size 1.27 1.27)
					(thickness 0.15)
				)
				(justify left bottom)
				(hide yes)
			)
		)
		(property "Footprint" "antmicro-footprints:C_0603_1608Metric_EIA"
			(at 204.47 93.98 0)
			(effects
				(font
					(size 1.27 1.27)
					(thickness 0.15)
				)
				(justify left bottom)
				(hide yes)
			)
		)
		(property "Datasheet" "https://product.samsungsem.com/mlcc/CL10A226MO7JZN.do"
			(at 201.93 93.98 0)
			(effects
				(font
					(size 1.27 1.27)
					(thickness 0.15)
				)
				(justify left bottom)
				(hide yes)
			)
		)
		(property "Description" "SMD Multilayer Ceramic Capacitor"
			(at 217.17 114.3 0)
			(effects
				(font
					(size 1.27 1.27)
				)
				(hide yes)
			)
		)
		(property "MPN" "CL10A226MO7JZNC"
			(at 199.39 93.98 0)
			(effects
				(font
					(size 1.27 1.27)
					(thickness 0.15)
				)
				(justify left bottom)
				(hide yes)
			)
		)
		(property "Manufacturer" "Samsung Electro-Mechanics"
			(at 196.85 93.98 0)
			(effects
				(font
					(size 1.27 1.27)
					(thickness 0.15)
				)
				(justify left bottom)
				(hide yes)
			)
		)
		(property "License" "Apache-2.0"
			(at 194.31 93.98 0)
			(effects
				(font
					(size 1.27 1.27)
					(thickness 0.15)
				)
				(justify left bottom)
				(hide yes)
			)
		)
		(property "Author" "Antmicro"
			(at 191.77 93.98 0)
			(effects
				(font
					(size 1.27 1.27)
					(thickness 0.15)
				)
				(justify left bottom)
				(hide yes)
			)
		)
		(property "Val" "22u"
			(at 215.138 113.03 90)
			(effects
				(font
					(size 1.27 1.27)
					(thickness 0.15)
				)
				(justify right)
			)
		)
		(property "Voltage" "16V"
			(at 214.63 114.2935 90)
			(effects
				(font
					(size 1.27 1.27)
				)
				(justify right)
				(hide yes)
			)
		)
		(property "Dielectric" ""
			(at 186.69 93.98 0)
			(effects
				(font
					(size 1.27 1.27)
				)
				(justify left bottom)
				(hide yes)
			)
		)
		(property "Public" "False"
			(at 184.15 93.98 0)
			(effects
				(font
					(size 1.27 1.27)
				)
				(justify left bottom)
				(hide yes)
			)
		)
		(pin "2"
		)
		(pin "1"
		)
		(instances
			(project "OCuLink to 10GbE adapter"
				(path ""
					(reference "C21")
					(unit 1)
				)
			)
		)
	)
	(symbol
		(lib_id "antmicropower:GND")
		(at 344.17 81.28 0)
		(unit 1)
		(exclude_from_sim no)
		(in_bom yes)
		(on_board yes)
		(dnp no)
		(property "Reference" "#PWR020"
			(at 353.06 83.82 0)
			(effects
				(font
					(size 1.27 1.27)
					(thickness 0.15)
				)
				(justify left bottom)
				(hide yes)
			)
		)
		(property "Value" "GND"
			(at 344.17 85.09 0)
			(effects
				(font
					(size 1.27 1.27)
					(thickness 0.15)
				)
			)
		)
		(property "Footprint" ""
			(at 353.06 88.9 0)
			(effects
				(font
					(size 1.27 1.27)
					(thickness 0.15)
				)
				(justify left bottom)
				(hide yes)
			)
		)
		(property "Datasheet" ""
			(at 353.06 93.98 0)
			(effects
				(font
					(size 1.27 1.27)
					(thickness 0.15)
				)
				(justify left bottom)
				(hide yes)
			)
		)
		(property "Description" ""
			(at 344.17 81.28 0)
			(effects
				(font
					(size 1.27 1.27)
				)
				(hide yes)
			)
		)
		(property "Author" "Antmicro"
			(at 353.06 88.9 0)
			(effects
				(font
					(size 1.27 1.27)
					(thickness 0.15)
				)
				(justify left bottom)
				(hide yes)
			)
		)
		(property "License" "Apache-2.0"
			(at 353.06 91.44 0)
			(effects
				(font
					(size 1.27 1.27)
					(thickness 0.15)
				)
				(justify left bottom)
				(hide yes)
			)
		)
		(pin "1"
		)
		(instances
			(project "OCuLink to 10GbE adapter"
				(path ""
					(reference "#PWR020")
					(unit 1)
				)
			)
		)
	)
	(symbol
		(lib_id "antmicropower:GND")
		(at 344.17 157.48 0)
		(unit 1)
		(exclude_from_sim no)
		(in_bom yes)
		(on_board yes)
		(dnp no)
		(property "Reference" "#PWR043"
			(at 353.06 160.02 0)
			(effects
				(font
					(size 1.27 1.27)
					(thickness 0.15)
				)
				(justify left bottom)
				(hide yes)
			)
		)
		(property "Value" "GND"
			(at 344.17 161.29 0)
			(effects
				(font
					(size 1.27 1.27)
					(thickness 0.15)
				)
			)
		)
		(property "Footprint" ""
			(at 353.06 165.1 0)
			(effects
				(font
					(size 1.27 1.27)
					(thickness 0.15)
				)
				(justify left bottom)
				(hide yes)
			)
		)
		(property "Datasheet" ""
			(at 353.06 170.18 0)
			(effects
				(font
					(size 1.27 1.27)
					(thickness 0.15)
				)
				(justify left bottom)
				(hide yes)
			)
		)
		(property "Description" ""
			(at 344.17 157.48 0)
			(effects
				(font
					(size 1.27 1.27)
				)
				(hide yes)
			)
		)
		(property "Author" "Antmicro"
			(at 353.06 165.1 0)
			(effects
				(font
					(size 1.27 1.27)
					(thickness 0.15)
				)
				(justify left bottom)
				(hide yes)
			)
		)
		(property "License" "Apache-2.0"
			(at 353.06 167.64 0)
			(effects
				(font
					(size 1.27 1.27)
					(thickness 0.15)
				)
				(justify left bottom)
				(hide yes)
			)
		)
		(pin "1"
		)
		(instances
			(project "OCuLink to 10GbE adapter"
				(path ""
					(reference "#PWR043")
					(unit 1)
				)
			)
		)
	)
	(symbol
		(lib_id "antmicropower:VCC")
		(at 217.17 137.16 0)
		(unit 1)
		(exclude_from_sim no)
		(in_bom yes)
		(on_board yes)
		(dnp no)
		(property "Reference" "#PWR0356"
			(at 217.17 140.97 0)
			(effects
				(font
					(size 1.27 1.27)
				)
				(hide yes)
			)
		)
		(property "Value" "VCC"
			(at 217.17 133.35 0)
			(effects
				(font
					(size 1.27 1.27)
				)
			)
		)
		(property "Footprint" ""
			(at 217.17 137.16 0)
			(effects
				(font
					(size 1.27 1.27)
				)
				(hide yes)
			)
		)
		(property "Datasheet" ""
			(at 217.17 137.16 0)
			(effects
				(font
					(size 1.27 1.27)
				)
				(hide yes)
			)
		)
		(property "Description" ""
			(at 217.17 143.51 0)
			(effects
				(font
					(size 1.27 1.27)
				)
				(justify left bottom)
				(hide yes)
			)
		)
		(pin "1"
		)
		(instances
			(project "oculink-to-10gbe-adapter"
				(path ""
					(reference "#PWR0356")
					(unit 1)
				)
			)
		)
	)
	(symbol
		(lib_id "antmicroTestPoints:TP_0.75mm_SMD")
		(at 358.14 100.33 90)
		(unit 1)
		(exclude_from_sim no)
		(in_bom no)
		(on_board yes)
		(dnp no)
		(property "Reference" "TP19"
			(at 358.14 95.25 90)
			(effects
				(font
					(size 1.27 1.27)
					(thickness 0.15)
				)
			)
		)
		(property "Value" "TP_0.75mm_SMD"
			(at 361.95 90.17 0)
			(effects
				(font
					(size 1.27 1.27)
					(thickness 0.15)
				)
				(justify left bottom)
				(hide yes)
			)
		)
		(property "Footprint" "antmicro-footprints:TP_SMD_0.75mm"
			(at 364.49 90.17 0)
			(effects
				(font
					(size 1.27 1.27)
					(thickness 0.15)
				)
				(justify left bottom)
				(hide yes)
			)
		)
		(property "Datasheet" ""
			(at 370.84 82.55 0)
			(effects
				(font
					(size 1.27 1.27)
					(thickness 0.15)
				)
				(justify left bottom)
				(hide yes)
			)
		)
		(property "Description" "SMT test point"
			(at 358.14 100.33 0)
			(effects
				(font
					(size 1.27 1.27)
				)
				(hide yes)
			)
		)
		(property "MPN" ""
			(at 369.57 89.535 0)
			(effects
				(font
					(size 1.27 1.27)
					(thickness 0.15)
				)
				(justify left bottom)
				(hide yes)
			)
		)
		(property "Manufacturer" ""
			(at 364.49 89.535 0)
			(effects
				(font
					(size 1.27 1.27)
					(thickness 0.15)
				)
				(justify left bottom)
				(hide yes)
			)
		)
		(property "Author" "Antmicro"
			(at 367.03 90.17 0)
			(effects
				(font
					(size 1.27 1.27)
					(thickness 0.15)
				)
				(justify left bottom)
				(hide yes)
			)
		)
		(property "License" "Apache-2.0"
			(at 369.57 90.17 0)
			(effects
				(font
					(size 1.27 1.27)
					(thickness 0.15)
				)
				(justify left bottom)
				(hide yes)
			)
		)
		(pin "1"
		)
		(instances
			(project "OCuLink to 10GbE adapter"
				(path ""
					(reference "TP19")
					(unit 1)
				)
			)
		)
	)
	(symbol
		(lib_id "antmicropower:PWR_FLAG")
		(at 391.16 99.06 0)
		(unit 1)
		(exclude_from_sim no)
		(in_bom yes)
		(on_board yes)
		(dnp no)
		(property "Reference" "#FLG05"
			(at 391.16 97.155 0)
			(effects
				(font
					(size 1.27 1.27)
				)
				(hide yes)
			)
		)
		(property "Value" "PWR_FLAG"
			(at 391.16 95.25 0)
			(effects
				(font
					(size 1.27 1.27)
				)
			)
		)
		(property "Footprint" ""
			(at 391.16 99.06 0)
			(effects
				(font
					(size 1.27 1.27)
				)
				(hide yes)
			)
		)
		(property "Datasheet" ""
			(at 391.16 99.06 0)
			(effects
				(font
					(size 1.27 1.27)
				)
				(hide yes)
			)
		)
		(property "Description" ""
			(at 391.16 99.06 0)
			(effects
				(font
					(size 1.27 1.27)
				)
				(hide yes)
			)
		)
		(pin "1"
		)
		(instances
			(project "OCuLink to 10GbE adapter"
				(path ""
					(reference "#FLG05")
					(unit 1)
				)
			)
		)
	)
	(symbol
		(lib_id "antmicroTransistorsBipolarSingle:DTC014T_SOT-416")
		(at 246.38 238.76 0)
		(unit 1)
		(exclude_from_sim no)
		(in_bom yes)
		(on_board yes)
		(dnp no)
		(property "Reference" "Q8"
			(at 255.778 240.03 0)
			(effects
				(font
					(size 1.27 1.27)
					(thickness 0.15)
				)
				(justify left)
			)
		)
		(property "Value" "DTC014T_SOT-416"
			(at 271.78 246.38 0)
			(effects
				(font
					(size 1.27 1.27)
					(thickness 0.15)
				)
				(justify left bottom)
				(hide yes)
			)
		)
		(property "Footprint" "antmicro-footprints:SOT-416"
			(at 271.78 248.92 0)
			(effects
				(font
					(size 1.27 1.27)
					(thickness 0.15)
				)
				(justify left bottom)
				(hide yes)
			)
		)
		(property "Datasheet" "https://www.rohm.com/datasheet?p=DTC014TEB&dist=Mouser&media=referral&source=mouser.com&campaign=Mouser"
			(at 271.78 251.46 0)
			(effects
				(font
					(size 1.27 1.27)
					(thickness 0.15)
				)
				(justify left bottom)
				(hide yes)
			)
		)
		(property "Description" "Bipolar (BJT) Single Transistor with built-in base resistor, NPN, 50V, 100mA, 150mW, SOT-416FL, Surface Mount"
			(at 271.78 264.16 0)
			(effects
				(font
					(size 1.27 1.27)
				)
				(justify left bottom)
				(hide yes)
			)
		)
		(property "Manufacturer" "ROHM Semiconductor"
			(at 271.78 254 0)
			(effects
				(font
					(size 1.27 1.27)
					(thickness 0.15)
				)
				(justify left bottom)
				(hide yes)
			)
		)
		(property "MPN" "DTC014TEBTL"
			(at 255.778 242.57 0)
			(effects
				(font
					(size 1.27 1.27)
					(thickness 0.15)
				)
				(justify left)
			)
		)
		(property "Author" "Antmicro"
			(at 271.78 259.08 0)
			(effects
				(font
					(size 1.27 1.27)
					(thickness 0.15)
				)
				(justify left bottom)
				(hide yes)
			)
		)
		(property "License" "Apache-2.0"
			(at 271.78 261.62 0)
			(effects
				(font
					(size 1.27 1.27)
					(thickness 0.15)
				)
				(justify left bottom)
				(hide yes)
			)
		)
		(pin "1"
		)
		(pin "2"
		)
		(pin "3"
		)
		(instances
			(project "oculink-to-10gbe-adapter"
				(path ""
					(reference "Q8")
					(unit 1)
				)
			)
		)
	)
	(symbol
		(lib_id "antmicroLEDIndicationDiscrete:LED_G_0603_LG_L29K-G2J1-24-Z")
		(at 177.8 223.52 90)
		(unit 1)
		(exclude_from_sim no)
		(in_bom yes)
		(on_board yes)
		(dnp no)
		(property "Reference" "D16"
			(at 179.07 219.71 90)
			(effects
				(font
					(size 1.27 1.27)
					(thickness 0.15)
				)
				(justify right)
			)
		)
		(property "Value" "LED_G_0603_LG_L29K-G2J1-24-Z"
			(at 185.42 203.2 0)
			(effects
				(font
					(size 1.27 1.27)
					(thickness 0.15)
				)
				(justify left bottom)
				(hide yes)
			)
		)
		(property "Footprint" "antmicro-footprints:LED_0603_1608Metric_G"
			(at 187.96 203.2 0)
			(effects
				(font
					(size 1.27 1.27)
					(thickness 0.15)
				)
				(justify left bottom)
				(hide yes)
			)
		)
		(property "Datasheet" "https://look.ams-osram.com/m/19ee86b3ae0ee95b/original/LG-L29K.pdf"
			(at 190.5 203.2 0)
			(effects
				(font
					(size 1.27 1.27)
					(thickness 0.15)
				)
				(justify left bottom)
				(hide yes)
			)
		)
		(property "Description" "LED, Green, SMD, 0603, 20 mA, 1.7 V, 570 nm"
			(at 177.8 223.52 0)
			(effects
				(font
					(size 1.27 1.27)
				)
				(hide yes)
			)
		)
		(property "MPN" "LG L29K-G2J1-24-Z"
			(at 193.04 203.2 0)
			(effects
				(font
					(size 1.27 1.27)
					(thickness 0.15)
				)
				(justify left bottom)
				(hide yes)
			)
		)
		(property "Manufacturer" "OSRAM"
			(at 195.58 203.2 0)
			(effects
				(font
					(size 1.27 1.27)
					(thickness 0.15)
				)
				(justify left bottom)
				(hide yes)
			)
		)
		(property "Color" "Green"
			(at 179.07 222.2499 90)
			(effects
				(font
					(size 1.27 1.27)
				)
				(justify right)
			)
		)
		(property "Author" "Antmicro"
			(at 198.12 203.2 0)
			(effects
				(font
					(size 1.27 1.27)
					(thickness 0.15)
				)
				(justify left bottom)
				(hide yes)
			)
		)
		(property "License" "Apache-2.0"
			(at 200.66 203.2 0)
			(effects
				(font
					(size 1.27 1.27)
					(thickness 0.15)
				)
				(justify left bottom)
				(hide yes)
			)
		)
		(pin "2"
		)
		(pin "1"
		)
		(instances
			(project "oculink-to-10gbe-adapter"
				(path ""
					(reference "D16")
					(unit 1)
				)
			)
		)
	)
	(symbol
		(lib_id "antmicroTestPoints:TP_0.75mm_SMD")
		(at 358.14 176.53 90)
		(unit 1)
		(exclude_from_sim no)
		(in_bom no)
		(on_board yes)
		(dnp no)
		(property "Reference" "TP17"
			(at 358.14 171.45 90)
			(effects
				(font
					(size 1.27 1.27)
					(thickness 0.15)
				)
			)
		)
		(property "Value" "TP_0.75mm_SMD"
			(at 361.95 166.37 0)
			(effects
				(font
					(size 1.27 1.27)
					(thickness 0.15)
				)
				(justify left bottom)
				(hide yes)
			)
		)
		(property "Footprint" "antmicro-footprints:TP_SMD_0.75mm"
			(at 364.49 166.37 0)
			(effects
				(font
					(size 1.27 1.27)
					(thickness 0.15)
				)
				(justify left bottom)
				(hide yes)
			)
		)
		(property "Datasheet" ""
			(at 370.84 158.75 0)
			(effects
				(font
					(size 1.27 1.27)
					(thickness 0.15)
				)
				(justify left bottom)
				(hide yes)
			)
		)
		(property "Description" "SMT test point"
			(at 358.14 176.53 0)
			(effects
				(font
					(size 1.27 1.27)
				)
				(hide yes)
			)
		)
		(property "MPN" ""
			(at 369.57 165.735 0)
			(effects
				(font
					(size 1.27 1.27)
					(thickness 0.15)
				)
				(justify left bottom)
				(hide yes)
			)
		)
		(property "Manufacturer" ""
			(at 364.49 165.735 0)
			(effects
				(font
					(size 1.27 1.27)
					(thickness 0.15)
				)
				(justify left bottom)
				(hide yes)
			)
		)
		(property "Author" "Antmicro"
			(at 367.03 166.37 0)
			(effects
				(font
					(size 1.27 1.27)
					(thickness 0.15)
				)
				(justify left bottom)
				(hide yes)
			)
		)
		(property "License" "Apache-2.0"
			(at 369.57 166.37 0)
			(effects
				(font
					(size 1.27 1.27)
					(thickness 0.15)
				)
				(justify left bottom)
				(hide yes)
			)
		)
		(pin "1"
		)
		(instances
			(project "OCuLink to 10GbE adapter"
				(path ""
					(reference "TP17")
					(unit 1)
				)
			)
		)
	)
	(symbol
		(lib_id "antmicroResistors0402:R_300R_0402")
		(at 48.26 167.64 270)
		(mirror x)
		(unit 1)
		(exclude_from_sim no)
		(in_bom yes)
		(on_board yes)
		(dnp no)
		(property "Reference" "R27"
			(at 46.99 163.83 90)
			(effects
				(font
					(size 1.27 1.27)
					(thickness 0.15)
				)
				(justify right)
			)
		)
		(property "Value" "R_300R_0402"
			(at 35.56 147.32 0)
			(effects
				(font
					(size 1.27 1.27)
					(thickness 0.15)
				)
				(justify left bottom)
				(hide yes)
			)
		)
		(property "Footprint" "antmicro-footprints:R_0402_1005Metric"
			(at 33.02 147.32 0)
			(effects
				(font
					(size 1.27 1.27)
					(thickness 0.15)
				)
				(justify left bottom)
				(hide yes)
			)
		)
		(property "Datasheet" "https://www.farnell.com/datasheets/3795017.pdf"
			(at 30.48 147.32 0)
			(effects
				(font
					(size 1.27 1.27)
					(thickness 0.15)
				)
				(justify left bottom)
				(hide yes)
			)
		)
		(property "Description" "MULTICOMP PRO MCMR04X3000FTLSMD Chip Resistor, Ceramic, 300 ohm, ± 1%, 62.5 mW, 0402 [1005 Metric], Thick Film"
			(at 48.26 167.64 0)
			(effects
				(font
					(size 1.27 1.27)
				)
				(hide yes)
			)
		)
		(property "MPN" "RMCF0402FT300R"
			(at 27.94 147.32 0)
			(effects
				(font
					(size 1.27 1.27)
					(thickness 0.15)
				)
				(justify left bottom)
				(hide yes)
			)
		)
		(property "Manufacturer" "Stackpole Electronics"
			(at 25.4 147.32 0)
			(effects
				(font
					(size 1.27 1.27)
					(thickness 0.15)
				)
				(justify left bottom)
				(hide yes)
			)
		)
		(property "License" "Apache-2.0"
			(at 22.86 147.32 0)
			(effects
				(font
					(size 1.27 1.27)
					(thickness 0.15)
				)
				(justify left bottom)
				(hide yes)
			)
		)
		(property "Author" "Antmicro"
			(at 20.32 147.32 0)
			(effects
				(font
					(size 1.27 1.27)
					(thickness 0.15)
				)
				(justify left bottom)
				(hide yes)
			)
		)
		(property "Val" "300R"
			(at 46.99 166.37 90)
			(effects
				(font
					(size 1.27 1.27)
					(thickness 0.15)
				)
				(justify right)
			)
		)
		(property "Tolerance" "1%"
			(at 38.1 147.32 0)
			(effects
				(font
					(size 1.27 1.27)
				)
				(justify left bottom)
				(hide yes)
			)
		)
		(pin "1"
		)
		(pin "2"
		)
		(instances
			(project "OCuLink to 10GbE adapter"
				(path ""
					(reference "R27")
					(unit 1)
				)
			)
		)
	)
	(symbol
		(lib_id "antmicropower:GND")
		(at 374.65 119.38 0)
		(unit 1)
		(exclude_from_sim no)
		(in_bom yes)
		(on_board yes)
		(dnp no)
		(property "Reference" "#PWR035"
			(at 383.54 121.92 0)
			(effects
				(font
					(size 1.27 1.27)
					(thickness 0.15)
				)
				(justify left bottom)
				(hide yes)
			)
		)
		(property "Value" "GND"
			(at 374.65 123.19 0)
			(effects
				(font
					(size 1.27 1.27)
					(thickness 0.15)
				)
			)
		)
		(property "Footprint" ""
			(at 383.54 127 0)
			(effects
				(font
					(size 1.27 1.27)
					(thickness 0.15)
				)
				(justify left bottom)
				(hide yes)
			)
		)
		(property "Datasheet" ""
			(at 383.54 132.08 0)
			(effects
				(font
					(size 1.27 1.27)
					(thickness 0.15)
				)
				(justify left bottom)
				(hide yes)
			)
		)
		(property "Description" ""
			(at 374.65 119.38 0)
			(effects
				(font
					(size 1.27 1.27)
				)
				(hide yes)
			)
		)
		(property "Author" "Antmicro"
			(at 383.54 127 0)
			(effects
				(font
					(size 1.27 1.27)
					(thickness 0.15)
				)
				(justify left bottom)
				(hide yes)
			)
		)
		(property "License" "Apache-2.0"
			(at 383.54 129.54 0)
			(effects
				(font
					(size 1.27 1.27)
					(thickness 0.15)
				)
				(justify left bottom)
				(hide yes)
			)
		)
		(pin "1"
		)
		(instances
			(project "OCuLink to 10GbE adapter"
				(path ""
					(reference "#PWR035")
					(unit 1)
				)
			)
		)
	)
	(symbol
		(lib_id "antmicropower:GND")
		(at 237.49 195.58 0)
		(unit 1)
		(exclude_from_sim no)
		(in_bom yes)
		(on_board yes)
		(dnp no)
		(property "Reference" "#PWR055"
			(at 246.38 198.12 0)
			(effects
				(font
					(size 1.27 1.27)
					(thickness 0.15)
				)
				(justify left bottom)
				(hide yes)
			)
		)
		(property "Value" "GND"
			(at 237.49 199.39 0)
			(effects
				(font
					(size 1.27 1.27)
					(thickness 0.15)
				)
			)
		)
		(property "Footprint" ""
			(at 246.38 203.2 0)
			(effects
				(font
					(size 1.27 1.27)
					(thickness 0.15)
				)
				(justify left bottom)
				(hide yes)
			)
		)
		(property "Datasheet" ""
			(at 246.38 208.28 0)
			(effects
				(font
					(size 1.27 1.27)
					(thickness 0.15)
				)
				(justify left bottom)
				(hide yes)
			)
		)
		(property "Description" ""
			(at 237.49 195.58 0)
			(effects
				(font
					(size 1.27 1.27)
				)
				(hide yes)
			)
		)
		(property "Author" "Antmicro"
			(at 246.38 203.2 0)
			(effects
				(font
					(size 1.27 1.27)
					(thickness 0.15)
				)
				(justify left bottom)
				(hide yes)
			)
		)
		(property "License" "Apache-2.0"
			(at 246.38 205.74 0)
			(effects
				(font
					(size 1.27 1.27)
					(thickness 0.15)
				)
				(justify left bottom)
				(hide yes)
			)
		)
		(pin "1"
		)
		(instances
			(project "OCuLink to 10GbE adapter"
				(path ""
					(reference "#PWR055")
					(unit 1)
				)
			)
		)
	)
	(symbol
		(lib_id "antmicropower:GND")
		(at 374.65 195.58 0)
		(unit 1)
		(exclude_from_sim no)
		(in_bom yes)
		(on_board yes)
		(dnp no)
		(property "Reference" "#PWR061"
			(at 383.54 198.12 0)
			(effects
				(font
					(size 1.27 1.27)
					(thickness 0.15)
				)
				(justify left bottom)
				(hide yes)
			)
		)
		(property "Value" "GND"
			(at 374.65 199.39 0)
			(effects
				(font
					(size 1.27 1.27)
					(thickness 0.15)
				)
			)
		)
		(property "Footprint" ""
			(at 383.54 203.2 0)
			(effects
				(font
					(size 1.27 1.27)
					(thickness 0.15)
				)
				(justify left bottom)
				(hide yes)
			)
		)
		(property "Datasheet" ""
			(at 383.54 208.28 0)
			(effects
				(font
					(size 1.27 1.27)
					(thickness 0.15)
				)
				(justify left bottom)
				(hide yes)
			)
		)
		(property "Description" ""
			(at 374.65 195.58 0)
			(effects
				(font
					(size 1.27 1.27)
				)
				(hide yes)
			)
		)
		(property "Author" "Antmicro"
			(at 383.54 203.2 0)
			(effects
				(font
					(size 1.27 1.27)
					(thickness 0.15)
				)
				(justify left bottom)
				(hide yes)
			)
		)
		(property "License" "Apache-2.0"
			(at 383.54 205.74 0)
			(effects
				(font
					(size 1.27 1.27)
					(thickness 0.15)
				)
				(justify left bottom)
				(hide yes)
			)
		)
		(pin "1"
		)
		(instances
			(project "OCuLink to 10GbE adapter"
				(path ""
					(reference "#PWR061")
					(unit 1)
				)
			)
		)
	)
	(symbol
		(lib_id "antmicropower:GND")
		(at 332.74 119.38 0)
		(unit 1)
		(exclude_from_sim no)
		(in_bom yes)
		(on_board yes)
		(dnp no)
		(property "Reference" "#PWR032"
			(at 341.63 121.92 0)
			(effects
				(font
					(size 1.27 1.27)
					(thickness 0.15)
				)
				(justify left bottom)
				(hide yes)
			)
		)
		(property "Value" "GND"
			(at 332.74 123.19 0)
			(effects
				(font
					(size 1.27 1.27)
					(thickness 0.15)
				)
			)
		)
		(property "Footprint" ""
			(at 341.63 127 0)
			(effects
				(font
					(size 1.27 1.27)
					(thickness 0.15)
				)
				(justify left bottom)
				(hide yes)
			)
		)
		(property "Datasheet" ""
			(at 341.63 132.08 0)
			(effects
				(font
					(size 1.27 1.27)
					(thickness 0.15)
				)
				(justify left bottom)
				(hide yes)
			)
		)
		(property "Description" ""
			(at 332.74 119.38 0)
			(effects
				(font
					(size 1.27 1.27)
				)
				(hide yes)
			)
		)
		(property "Author" "Antmicro"
			(at 341.63 127 0)
			(effects
				(font
					(size 1.27 1.27)
					(thickness 0.15)
				)
				(justify left bottom)
				(hide yes)
			)
		)
		(property "License" "Apache-2.0"
			(at 341.63 129.54 0)
			(effects
				(font
					(size 1.27 1.27)
					(thickness 0.15)
				)
				(justify left bottom)
				(hide yes)
			)
		)
		(pin "1"
		)
		(instances
			(project "OCuLink to 10GbE adapter"
				(path ""
					(reference "#PWR032")
					(unit 1)
				)
			)
		)
	)
	(symbol
		(lib_id "antmicroTestPoints:TP_0.75mm_SMD")
		(at 350.52 138.43 90)
		(unit 1)
		(exclude_from_sim no)
		(in_bom no)
		(on_board yes)
		(dnp no)
		(property "Reference" "TP40"
			(at 350.52 133.35 90)
			(effects
				(font
					(size 1.27 1.27)
					(thickness 0.15)
				)
			)
		)
		(property "Value" "TP_0.75mm_SMD"
			(at 354.33 128.27 0)
			(effects
				(font
					(size 1.27 1.27)
					(thickness 0.15)
				)
				(justify left bottom)
				(hide yes)
			)
		)
		(property "Footprint" "antmicro-footprints:TP_SMD_0.75mm"
			(at 356.87 128.27 0)
			(effects
				(font
					(size 1.27 1.27)
					(thickness 0.15)
				)
				(justify left bottom)
				(hide yes)
			)
		)
		(property "Datasheet" ""
			(at 363.22 120.65 0)
			(effects
				(font
					(size 1.27 1.27)
					(thickness 0.15)
				)
				(justify left bottom)
				(hide yes)
			)
		)
		(property "Description" "SMT test point"
			(at 350.52 138.43 0)
			(effects
				(font
					(size 1.27 1.27)
				)
				(hide yes)
			)
		)
		(property "MPN" ""
			(at 361.95 127.635 0)
			(effects
				(font
					(size 1.27 1.27)
					(thickness 0.15)
				)
				(justify left bottom)
				(hide yes)
			)
		)
		(property "Manufacturer" ""
			(at 356.87 127.635 0)
			(effects
				(font
					(size 1.27 1.27)
					(thickness 0.15)
				)
				(justify left bottom)
				(hide yes)
			)
		)
		(property "Author" "Antmicro"
			(at 359.41 128.27 0)
			(effects
				(font
					(size 1.27 1.27)
					(thickness 0.15)
				)
				(justify left bottom)
				(hide yes)
			)
		)
		(property "License" "Apache-2.0"
			(at 361.95 128.27 0)
			(effects
				(font
					(size 1.27 1.27)
					(thickness 0.15)
				)
				(justify left bottom)
				(hide yes)
			)
		)
		(pin "1"
		)
		(instances
			(project "oculink-to-10gbe-adapter"
				(path ""
					(reference "TP40")
					(unit 1)
				)
			)
		)
	)
	(symbol
		(lib_id "antmicroCapacitors0402:C_100n_0402")
		(at 374.65 190.5 90)
		(unit 1)
		(exclude_from_sim no)
		(in_bom yes)
		(on_board yes)
		(dnp no)
		(property "Reference" "C46"
			(at 376.428 186.69 90)
			(effects
				(font
					(size 1.27 1.27)
					(thickness 0.15)
				)
				(justify right)
			)
		)
		(property "Value" "C_100n_0402"
			(at 384.81 170.18 0)
			(effects
				(font
					(size 1.27 1.27)
					(thickness 0.15)
				)
				(justify left bottom)
				(hide yes)
			)
		)
		(property "Footprint" "antmicro-footprints:C_0402_1005Metric"
			(at 387.35 170.18 0)
			(effects
				(font
					(size 1.27 1.27)
					(thickness 0.15)
				)
				(justify left bottom)
				(hide yes)
			)
		)
		(property "Datasheet" "https://www.murata.com/products/productdetail?partno=GRM155R61H104KE14%23"
			(at 389.89 170.18 0)
			(effects
				(font
					(size 1.27 1.27)
					(thickness 0.15)
				)
				(justify left bottom)
				(hide yes)
			)
		)
		(property "Description" "SMD Multilayer Ceramic Capacitor, 0.1 µF, 50 V, 0402 [1005 Metric], ± 10%, X5R, GRM Series"
			(at 407.67 170.18 0)
			(effects
				(font
					(size 1.27 1.27)
				)
				(justify left bottom)
				(hide yes)
			)
		)
		(property "MPN" "GRM155R61H104KE14D"
			(at 392.43 170.18 0)
			(effects
				(font
					(size 1.27 1.27)
					(thickness 0.15)
				)
				(justify left bottom)
				(hide yes)
			)
		)
		(property "Manufacturer" "Murata"
			(at 394.97 170.18 0)
			(effects
				(font
					(size 1.27 1.27)
					(thickness 0.15)
				)
				(justify left bottom)
				(hide yes)
			)
		)
		(property "License" "Apache-2.0"
			(at 397.51 170.18 0)
			(effects
				(font
					(size 1.27 1.27)
					(thickness 0.15)
				)
				(justify left bottom)
				(hide yes)
			)
		)
		(property "Author" "Antmicro"
			(at 400.05 170.18 0)
			(effects
				(font
					(size 1.27 1.27)
					(thickness 0.15)
				)
				(justify left bottom)
				(hide yes)
			)
		)
		(property "Val" "100n"
			(at 376.428 189.23 90)
			(effects
				(font
					(size 1.27 1.27)
					(thickness 0.15)
				)
				(justify right)
			)
		)
		(property "Voltage" "50V"
			(at 402.59 170.18 0)
			(effects
				(font
					(size 1.27 1.27)
				)
				(justify left bottom)
				(hide yes)
			)
		)
		(property "Dielectric" "X5R"
			(at 405.13 170.18 0)
			(effects
				(font
					(size 1.27 1.27)
				)
				(justify left bottom)
				(hide yes)
			)
		)
		(pin "1"
		)
		(pin "2"
		)
		(instances
			(project "OCuLink to 10GbE adapter"
				(path ""
					(reference "C46")
					(unit 1)
				)
			)
		)
	)
	(symbol
		(lib_id "antmicroResistors0603:R_0R_22.4A_0603")
		(at 379.73 25.4 0)
		(unit 1)
		(exclude_from_sim no)
		(in_bom yes)
		(on_board yes)
		(dnp no)
		(property "Reference" "R1"
			(at 379.73 24.13 0)
			(effects
				(font
					(size 1.27 1.27)
					(thickness 0.15)
				)
				(justify right)
			)
		)
		(property "Value" "R_0R_22.4A_0603"
			(at 394.97 30.48 0)
			(effects
				(font
					(size 1.27 1.27)
					(thickness 0.15)
				)
				(justify left bottom)
				(hide yes)
			)
		)
		(property "Footprint" "antmicro-footprints:R_0603_1608Metric"
			(at 394.97 35.56 0)
			(effects
				(font
					(size 1.27 1.27)
					(thickness 0.15)
				)
				(justify left bottom)
				(hide yes)
			)
		)
		(property "Datasheet" "https://fscdn.rohm.com/en/products/databook/datasheet/passive/resistor/chip_resistor/pmr-jpw-e.pdf"
			(at 394.97 38.1 0)
			(effects
				(font
					(size 1.27 1.27)
					(thickness 0.15)
				)
				(justify left bottom)
				(hide yes)
			)
		)
		(property "Description" "SMD Chip Resistor"
			(at 394.97 53.34 0)
			(effects
				(font
					(size 1.27 1.27)
				)
				(justify left bottom)
				(hide yes)
			)
		)
		(property "MPN" "PMR03EZPJ000"
			(at 394.97 40.64 0)
			(effects
				(font
					(size 1.27 1.27)
					(thickness 0.15)
				)
				(justify left bottom)
				(hide yes)
			)
		)
		(property "Manufacturer" "ROHM Semiconductor"
			(at 394.97 43.18 0)
			(effects
				(font
					(size 1.27 1.27)
					(thickness 0.15)
				)
				(justify left bottom)
				(hide yes)
			)
		)
		(property "Val" "0R"
			(at 384.81 24.13 0)
			(effects
				(font
					(size 1.27 1.27)
					(thickness 0.15)
				)
				(justify left)
			)
		)
		(property "Max. Curr." "22.4A"
			(at 382.27 27.94 0)
			(effects
				(font
					(size 1.27 1.27)
					(thickness 0.15)
				)
			)
		)
		(property "Author" "Antmicro"
			(at 394.97 48.26 0)
			(effects
				(font
					(size 1.27 1.27)
					(thickness 0.15)
				)
				(justify left bottom)
				(hide yes)
			)
		)
		(property "License" "Apache-2.0"
			(at 394.97 50.8 0)
			(effects
				(font
					(size 1.27 1.27)
					(thickness 0.15)
				)
				(justify left bottom)
				(hide yes)
			)
		)
		(property "Tolerance" "template_tolerance"
			(at 400.05 35.56 0)
			(effects
				(font
					(size 1.27 1.27)
				)
				(justify left bottom)
				(hide yes)
			)
		)
		(pin "1"
		)
		(pin "2"
		)
		(instances
			(project "OCuLink to 10GbE adapter"
				(path ""
					(reference "R1")
					(unit 1)
				)
			)
		)
	)
	(symbol
		(lib_id "antmicropower:+1V0")
		(at 387.35 236.22 90)
		(unit 1)
		(exclude_from_sim no)
		(in_bom yes)
		(on_board yes)
		(dnp no)
		(fields_autoplaced yes)
		(property "Reference" "#PWR0308"
			(at 391.16 236.22 0)
			(effects
				(font
					(size 1.27 1.27)
				)
				(hide yes)
			)
		)
		(property "Value" "+1V0"
			(at 383.54 236.2199 90)
			(effects
				(font
					(size 1.27 1.27)
				)
				(justify left)
			)
		)
		(property "Footprint" ""
			(at 387.35 236.22 0)
			(effects
				(font
					(size 1.27 1.27)
				)
				(hide yes)
			)
		)
		(property "Datasheet" ""
			(at 387.35 236.22 0)
			(effects
				(font
					(size 1.27 1.27)
				)
				(hide yes)
			)
		)
		(property "Description" ""
			(at 387.35 236.22 0)
			(effects
				(font
					(size 1.27 1.27)
				)
				(hide yes)
			)
		)
		(pin "1"
		)
		(instances
			(project "oculink-to-10gbe-adapter"
				(path ""
					(reference "#PWR0308")
					(unit 1)
				)
			)
		)
	)
	(symbol
		(lib_id "antmicroLEDIndicationDiscrete:LED_G_0603_LG_L29K-G2J1-24-Z")
		(at 304.8 228.6 90)
		(unit 1)
		(exclude_from_sim no)
		(in_bom yes)
		(on_board yes)
		(dnp no)
		(property "Reference" "D11"
			(at 306.07 224.79 90)
			(effects
				(font
					(size 1.27 1.27)
					(thickness 0.15)
				)
				(justify right)
			)
		)
		(property "Value" "LED_G_0603_LG_L29K-G2J1-24-Z"
			(at 312.42 208.28 0)
			(effects
				(font
					(size 1.27 1.27)
					(thickness 0.15)
				)
				(justify left bottom)
				(hide yes)
			)
		)
		(property "Footprint" "antmicro-footprints:LED_0603_1608Metric_G"
			(at 314.96 208.28 0)
			(effects
				(font
					(size 1.27 1.27)
					(thickness 0.15)
				)
				(justify left bottom)
				(hide yes)
			)
		)
		(property "Datasheet" "https://look.ams-osram.com/m/19ee86b3ae0ee95b/original/LG-L29K.pdf"
			(at 317.5 208.28 0)
			(effects
				(font
					(size 1.27 1.27)
					(thickness 0.15)
				)
				(justify left bottom)
				(hide yes)
			)
		)
		(property "Description" "LED, Green, SMD, 0603, 20 mA, 1.7 V, 570 nm"
			(at 304.8 228.6 0)
			(effects
				(font
					(size 1.27 1.27)
				)
				(hide yes)
			)
		)
		(property "MPN" "LG L29K-G2J1-24-Z"
			(at 320.04 208.28 0)
			(effects
				(font
					(size 1.27 1.27)
					(thickness 0.15)
				)
				(justify left bottom)
				(hide yes)
			)
		)
		(property "Manufacturer" "OSRAM"
			(at 322.58 208.28 0)
			(effects
				(font
					(size 1.27 1.27)
					(thickness 0.15)
				)
				(justify left bottom)
				(hide yes)
			)
		)
		(property "Color" "Green"
			(at 306.07 227.3299 90)
			(effects
				(font
					(size 1.27 1.27)
				)
				(justify right)
			)
		)
		(property "Author" "Antmicro"
			(at 325.12 208.28 0)
			(effects
				(font
					(size 1.27 1.27)
					(thickness 0.15)
				)
				(justify left bottom)
				(hide yes)
			)
		)
		(property "License" "Apache-2.0"
			(at 327.66 208.28 0)
			(effects
				(font
					(size 1.27 1.27)
					(thickness 0.15)
				)
				(justify left bottom)
				(hide yes)
			)
		)
		(pin "2"
		)
		(pin "1"
		)
		(instances
			(project "OCuLink to 10GbE adapter"
				(path ""
					(reference "D11")
					(unit 1)
				)
			)
		)
	)
	(symbol
		(lib_id "antmicropower:GND")
		(at 297.18 157.48 0)
		(unit 1)
		(exclude_from_sim no)
		(in_bom yes)
		(on_board yes)
		(dnp no)
		(property "Reference" "#PWR041"
			(at 306.07 160.02 0)
			(effects
				(font
					(size 1.27 1.27)
					(thickness 0.15)
				)
				(justify left bottom)
				(hide yes)
			)
		)
		(property "Value" "GND"
			(at 297.18 161.29 0)
			(effects
				(font
					(size 1.27 1.27)
					(thickness 0.15)
				)
			)
		)
		(property "Footprint" ""
			(at 306.07 165.1 0)
			(effects
				(font
					(size 1.27 1.27)
					(thickness 0.15)
				)
				(justify left bottom)
				(hide yes)
			)
		)
		(property "Datasheet" ""
			(at 306.07 170.18 0)
			(effects
				(font
					(size 1.27 1.27)
					(thickness 0.15)
				)
				(justify left bottom)
				(hide yes)
			)
		)
		(property "Description" ""
			(at 297.18 157.48 0)
			(effects
				(font
					(size 1.27 1.27)
				)
				(hide yes)
			)
		)
		(property "Author" "Antmicro"
			(at 306.07 165.1 0)
			(effects
				(font
					(size 1.27 1.27)
					(thickness 0.15)
				)
				(justify left bottom)
				(hide yes)
			)
		)
		(property "License" "Apache-2.0"
			(at 306.07 167.64 0)
			(effects
				(font
					(size 1.27 1.27)
					(thickness 0.15)
				)
				(justify left bottom)
				(hide yes)
			)
		)
		(pin "1"
		)
		(instances
			(project "OCuLink to 10GbE adapter"
				(path ""
					(reference "#PWR041")
					(unit 1)
				)
			)
		)
	)
	(symbol
		(lib_id "antmicropower:GND")
		(at 217.17 81.28 0)
		(unit 1)
		(exclude_from_sim no)
		(in_bom yes)
		(on_board yes)
		(dnp no)
		(property "Reference" "#PWR014"
			(at 226.06 83.82 0)
			(effects
				(font
					(size 1.27 1.27)
					(thickness 0.15)
				)
				(justify left bottom)
				(hide yes)
			)
		)
		(property "Value" "GND"
			(at 217.17 85.09 0)
			(effects
				(font
					(size 1.27 1.27)
					(thickness 0.15)
				)
			)
		)
		(property "Footprint" ""
			(at 226.06 88.9 0)
			(effects
				(font
					(size 1.27 1.27)
					(thickness 0.15)
				)
				(justify left bottom)
				(hide yes)
			)
		)
		(property "Datasheet" ""
			(at 226.06 93.98 0)
			(effects
				(font
					(size 1.27 1.27)
					(thickness 0.15)
				)
				(justify left bottom)
				(hide yes)
			)
		)
		(property "Description" ""
			(at 217.17 81.28 0)
			(effects
				(font
					(size 1.27 1.27)
				)
				(hide yes)
			)
		)
		(property "Author" "Antmicro"
			(at 226.06 88.9 0)
			(effects
				(font
					(size 1.27 1.27)
					(thickness 0.15)
				)
				(justify left bottom)
				(hide yes)
			)
		)
		(property "License" "Apache-2.0"
			(at 226.06 91.44 0)
			(effects
				(font
					(size 1.27 1.27)
					(thickness 0.15)
				)
				(justify left bottom)
				(hide yes)
			)
		)
		(pin "1"
		)
		(instances
			(project "OCuLink to 10GbE adapter"
				(path ""
					(reference "#PWR014")
					(unit 1)
				)
			)
		)
	)
	(symbol
		(lib_id "antmicropower:GND")
		(at 247.65 195.58 0)
		(unit 1)
		(exclude_from_sim no)
		(in_bom yes)
		(on_board yes)
		(dnp no)
		(property "Reference" "#PWR056"
			(at 256.54 198.12 0)
			(effects
				(font
					(size 1.27 1.27)
					(thickness 0.15)
				)
				(justify left bottom)
				(hide yes)
			)
		)
		(property "Value" "GND"
			(at 247.65 199.39 0)
			(effects
				(font
					(size 1.27 1.27)
					(thickness 0.15)
				)
			)
		)
		(property "Footprint" ""
			(at 256.54 203.2 0)
			(effects
				(font
					(size 1.27 1.27)
					(thickness 0.15)
				)
				(justify left bottom)
				(hide yes)
			)
		)
		(property "Datasheet" ""
			(at 256.54 208.28 0)
			(effects
				(font
					(size 1.27 1.27)
					(thickness 0.15)
				)
				(justify left bottom)
				(hide yes)
			)
		)
		(property "Description" ""
			(at 247.65 195.58 0)
			(effects
				(font
					(size 1.27 1.27)
				)
				(hide yes)
			)
		)
		(property "Author" "Antmicro"
			(at 256.54 203.2 0)
			(effects
				(font
					(size 1.27 1.27)
					(thickness 0.15)
				)
				(justify left bottom)
				(hide yes)
			)
		)
		(property "License" "Apache-2.0"
			(at 256.54 205.74 0)
			(effects
				(font
					(size 1.27 1.27)
					(thickness 0.15)
				)
				(justify left bottom)
				(hide yes)
			)
		)
		(pin "1"
		)
		(instances
			(project "OCuLink to 10GbE adapter"
				(path ""
					(reference "#PWR056")
					(unit 1)
				)
			)
		)
	)
	(symbol
		(lib_id "antmicropower:GND")
		(at 354.33 157.48 0)
		(unit 1)
		(exclude_from_sim no)
		(in_bom yes)
		(on_board yes)
		(dnp no)
		(property "Reference" "#PWR044"
			(at 363.22 160.02 0)
			(effects
				(font
					(size 1.27 1.27)
					(thickness 0.15)
				)
				(justify left bottom)
				(hide yes)
			)
		)
		(property "Value" "GND"
			(at 354.33 161.29 0)
			(effects
				(font
					(size 1.27 1.27)
					(thickness 0.15)
				)
			)
		)
		(property "Footprint" ""
			(at 363.22 165.1 0)
			(effects
				(font
					(size 1.27 1.27)
					(thickness 0.15)
				)
				(justify left bottom)
				(hide yes)
			)
		)
		(property "Datasheet" ""
			(at 363.22 170.18 0)
			(effects
				(font
					(size 1.27 1.27)
					(thickness 0.15)
				)
				(justify left bottom)
				(hide yes)
			)
		)
		(property "Description" ""
			(at 354.33 157.48 0)
			(effects
				(font
					(size 1.27 1.27)
				)
				(hide yes)
			)
		)
		(property "Author" "Antmicro"
			(at 363.22 165.1 0)
			(effects
				(font
					(size 1.27 1.27)
					(thickness 0.15)
				)
				(justify left bottom)
				(hide yes)
			)
		)
		(property "License" "Apache-2.0"
			(at 363.22 167.64 0)
			(effects
				(font
					(size 1.27 1.27)
					(thickness 0.15)
				)
				(justify left bottom)
				(hide yes)
			)
		)
		(pin "1"
		)
		(instances
			(project "OCuLink to 10GbE adapter"
				(path ""
					(reference "#PWR044")
					(unit 1)
				)
			)
		)
	)
	(symbol
		(lib_id "antmicroResistors0402:R_255k_0402")
		(at 196.85 31.75 270)
		(mirror x)
		(unit 1)
		(exclude_from_sim no)
		(in_bom yes)
		(on_board yes)
		(dnp no)
		(property "Reference" "R2"
			(at 195.58 27.94 90)
			(effects
				(font
					(size 1.27 1.27)
					(thickness 0.15)
				)
				(justify right)
			)
		)
		(property "Value" "R_255k_0402"
			(at 184.15 11.43 0)
			(effects
				(font
					(size 1.27 1.27)
					(thickness 0.15)
				)
				(justify left bottom)
				(hide yes)
			)
		)
		(property "Footprint" "antmicro-footprints:R_0402_1005Metric"
			(at 181.61 11.43 0)
			(effects
				(font
					(size 1.27 1.27)
					(thickness 0.15)
				)
				(justify left bottom)
				(hide yes)
			)
		)
		(property "Datasheet" "https://www.bourns.com/docs/product-datasheets/cr.pdf"
			(at 179.07 11.43 0)
			(effects
				(font
					(size 1.27 1.27)
					(thickness 0.15)
				)
				(justify left bottom)
				(hide yes)
			)
		)
		(property "Description" "SMD Chip Resistor, 255 kohm, ± 1%, 100 mW, 0402 [1005 Metric], Thick Film, Precision"
			(at 166.37 11.43 0)
			(effects
				(font
					(size 1.27 1.27)
				)
				(justify left bottom)
				(hide yes)
			)
		)
		(property "MPN" "CR0402-FX-2553GLF"
			(at 176.53 11.43 0)
			(effects
				(font
					(size 1.27 1.27)
					(thickness 0.15)
				)
				(justify left bottom)
				(hide yes)
			)
		)
		(property "Manufacturer" "Bourns"
			(at 173.99 11.43 0)
			(effects
				(font
					(size 1.27 1.27)
					(thickness 0.15)
				)
				(justify left bottom)
				(hide yes)
			)
		)
		(property "License" "Apache-2.0"
			(at 171.45 11.43 0)
			(effects
				(font
					(size 1.27 1.27)
					(thickness 0.15)
				)
				(justify left bottom)
				(hide yes)
			)
		)
		(property "Author" "Antmicro"
			(at 168.91 11.43 0)
			(effects
				(font
					(size 1.27 1.27)
					(thickness 0.15)
				)
				(justify left bottom)
				(hide yes)
			)
		)
		(property "Val" "255k"
			(at 195.58 30.48 90)
			(effects
				(font
					(size 1.27 1.27)
					(thickness 0.15)
				)
				(justify right)
			)
		)
		(property "Tolerance" "1%"
			(at 186.69 11.43 0)
			(effects
				(font
					(size 1.27 1.27)
				)
				(justify left bottom)
				(hide yes)
			)
		)
		(pin "2"
		)
		(pin "1"
		)
		(instances
			(project ""
				(path ""
					(reference "R2")
					(unit 1)
				)
			)
		)
	)
	(symbol
		(lib_id "antmicroCapacitors0402:C_1u_25V_0402")
		(at 247.65 76.2 270)
		(mirror x)
		(unit 1)
		(exclude_from_sim no)
		(in_bom yes)
		(on_board yes)
		(dnp no)
		(property "Reference" "C15"
			(at 245.872 72.39 90)
			(effects
				(font
					(size 1.27 1.27)
					(thickness 0.15)
				)
				(justify right)
			)
		)
		(property "Value" "C_1u_25V_0402"
			(at 237.49 55.88 0)
			(effects
				(font
					(size 1.27 1.27)
					(thickness 0.15)
				)
				(justify left bottom)
				(hide yes)
			)
		)
		(property "Footprint" "antmicro-footprints:C_0402_1005Metric"
			(at 234.95 55.88 0)
			(effects
				(font
					(size 1.27 1.27)
					(thickness 0.15)
				)
				(justify left bottom)
				(hide yes)
			)
		)
		(property "Datasheet" "https://www.murata.com/products/productdetail?partno=GRM155R61E105KE11%23"
			(at 232.41 55.88 0)
			(effects
				(font
					(size 1.27 1.27)
					(thickness 0.15)
				)
				(justify left bottom)
				(hide yes)
			)
		)
		(property "Description" "SMD Multilayer Ceramic Capacitor, 1 µF, 25 V, 0402 [1005 Metric], ± 10%, X5R, GRM Series"
			(at 214.63 55.88 0)
			(effects
				(font
					(size 1.27 1.27)
				)
				(justify left bottom)
				(hide yes)
			)
		)
		(property "MPN" "GRM155R61E105KE11J"
			(at 229.87 55.88 0)
			(effects
				(font
					(size 1.27 1.27)
					(thickness 0.15)
				)
				(justify left bottom)
				(hide yes)
			)
		)
		(property "Manufacturer" "Murata"
			(at 227.33 55.88 0)
			(effects
				(font
					(size 1.27 1.27)
					(thickness 0.15)
				)
				(justify left bottom)
				(hide yes)
			)
		)
		(property "License" "Apache-2.0"
			(at 224.79 55.88 0)
			(effects
				(font
					(size 1.27 1.27)
					(thickness 0.15)
				)
				(justify left bottom)
				(hide yes)
			)
		)
		(property "Author" "Antmicro"
			(at 222.25 55.88 0)
			(effects
				(font
					(size 1.27 1.27)
					(thickness 0.15)
				)
				(justify left bottom)
				(hide yes)
			)
		)
		(property "Val" "1u"
			(at 245.872 74.93 90)
			(effects
				(font
					(size 1.27 1.27)
					(thickness 0.15)
				)
				(justify right)
			)
		)
		(property "Voltage" "25V"
			(at 219.71 55.88 0)
			(effects
				(font
					(size 1.27 1.27)
				)
				(justify left bottom)
				(hide yes)
			)
		)
		(property "Dielectric" "X5R"
			(at 217.17 55.88 0)
			(effects
				(font
					(size 1.27 1.27)
				)
				(justify left bottom)
				(hide yes)
			)
		)
		(pin "2"
		)
		(pin "1"
		)
		(instances
			(project "OCuLink to 10GbE adapter"
				(path ""
					(reference "C15")
					(unit 1)
				)
			)
		)
	)
	(symbol
		(lib_id "antmicroCapacitors0603:C_22u_16V_0603")
		(at 227.33 38.1 270)
		(mirror x)
		(unit 1)
		(exclude_from_sim no)
		(in_bom yes)
		(on_board yes)
		(dnp no)
		(property "Reference" "C4"
			(at 225.552 34.29 90)
			(effects
				(font
					(size 1.27 1.27)
					(thickness 0.15)
				)
				(justify right)
			)
		)
		(property "Value" "C_22u_16V_0603"
			(at 217.17 17.78 0)
			(effects
				(font
					(size 1.27 1.27)
					(thickness 0.15)
				)
				(justify left bottom)
				(hide yes)
			)
		)
		(property "Footprint" "antmicro-footprints:C_0603_1608Metric_EIA"
			(at 214.63 17.78 0)
			(effects
				(font
					(size 1.27 1.27)
					(thickness 0.15)
				)
				(justify left bottom)
				(hide yes)
			)
		)
		(property "Datasheet" "https://product.samsungsem.com/mlcc/CL10A226MO7JZN.do"
			(at 212.09 17.78 0)
			(effects
				(font
					(size 1.27 1.27)
					(thickness 0.15)
				)
				(justify left bottom)
				(hide yes)
			)
		)
		(property "Description" "SMD Multilayer Ceramic Capacitor"
			(at 227.33 38.1 0)
			(effects
				(font
					(size 1.27 1.27)
				)
				(hide yes)
			)
		)
		(property "MPN" "CL10A226MO7JZNC"
			(at 209.55 17.78 0)
			(effects
				(font
					(size 1.27 1.27)
					(thickness 0.15)
				)
				(justify left bottom)
				(hide yes)
			)
		)
		(property "Manufacturer" "Samsung Electro-Mechanics"
			(at 207.01 17.78 0)
			(effects
				(font
					(size 1.27 1.27)
					(thickness 0.15)
				)
				(justify left bottom)
				(hide yes)
			)
		)
		(property "License" "Apache-2.0"
			(at 204.47 17.78 0)
			(effects
				(font
					(size 1.27 1.27)
					(thickness 0.15)
				)
				(justify left bottom)
				(hide yes)
			)
		)
		(property "Author" "Antmicro"
			(at 201.93 17.78 0)
			(effects
				(font
					(size 1.27 1.27)
					(thickness 0.15)
				)
				(justify left bottom)
				(hide yes)
			)
		)
		(property "Val" "22u"
			(at 225.552 36.83 90)
			(effects
				(font
					(size 1.27 1.27)
					(thickness 0.15)
				)
				(justify right)
			)
		)
		(property "Voltage" "16V"
			(at 224.79 38.0935 90)
			(effects
				(font
					(size 1.27 1.27)
				)
				(justify right)
				(hide yes)
			)
		)
		(property "Dielectric" ""
			(at 196.85 17.78 0)
			(effects
				(font
					(size 1.27 1.27)
				)
				(justify left bottom)
				(hide yes)
			)
		)
		(property "Public" "False"
			(at 194.31 17.78 0)
			(effects
				(font
					(size 1.27 1.27)
				)
				(justify left bottom)
				(hide yes)
			)
		)
		(pin "2"
		)
		(pin "1"
		)
		(instances
			(project "OCuLink to 10GbE adapter"
				(path ""
					(reference "C4")
					(unit 1)
				)
			)
		)
	)
	(symbol
		(lib_id "antmicroCapacitors0402:C_1u_25V_0402")
		(at 247.65 190.5 270)
		(mirror x)
		(unit 1)
		(exclude_from_sim no)
		(in_bom yes)
		(on_board yes)
		(dnp no)
		(property "Reference" "C43"
			(at 245.872 186.69 90)
			(effects
				(font
					(size 1.27 1.27)
					(thickness 0.15)
				)
				(justify right)
			)
		)
		(property "Value" "C_1u_25V_0402"
			(at 237.49 170.18 0)
			(effects
				(font
					(size 1.27 1.27)
					(thickness 0.15)
				)
				(justify left bottom)
				(hide yes)
			)
		)
		(property "Footprint" "antmicro-footprints:C_0402_1005Metric"
			(at 234.95 170.18 0)
			(effects
				(font
					(size 1.27 1.27)
					(thickness 0.15)
				)
				(justify left bottom)
				(hide yes)
			)
		)
		(property "Datasheet" "https://www.murata.com/products/productdetail?partno=GRM155R61E105KE11%23"
			(at 232.41 170.18 0)
			(effects
				(font
					(size 1.27 1.27)
					(thickness 0.15)
				)
				(justify left bottom)
				(hide yes)
			)
		)
		(property "Description" "SMD Multilayer Ceramic Capacitor, 1 µF, 25 V, 0402 [1005 Metric], ± 10%, X5R, GRM Series"
			(at 214.63 170.18 0)
			(effects
				(font
					(size 1.27 1.27)
				)
				(justify left bottom)
				(hide yes)
			)
		)
		(property "MPN" "GRM155R61E105KE11J"
			(at 229.87 170.18 0)
			(effects
				(font
					(size 1.27 1.27)
					(thickness 0.15)
				)
				(justify left bottom)
				(hide yes)
			)
		)
		(property "Manufacturer" "Murata"
			(at 227.33 170.18 0)
			(effects
				(font
					(size 1.27 1.27)
					(thickness 0.15)
				)
				(justify left bottom)
				(hide yes)
			)
		)
		(property "License" "Apache-2.0"
			(at 224.79 170.18 0)
			(effects
				(font
					(size 1.27 1.27)
					(thickness 0.15)
				)
				(justify left bottom)
				(hide yes)
			)
		)
		(property "Author" "Antmicro"
			(at 222.25 170.18 0)
			(effects
				(font
					(size 1.27 1.27)
					(thickness 0.15)
				)
				(justify left bottom)
				(hide yes)
			)
		)
		(property "Val" "1u"
			(at 245.872 189.23 90)
			(effects
				(font
					(size 1.27 1.27)
					(thickness 0.15)
				)
				(justify right)
			)
		)
		(property "Voltage" "25V"
			(at 219.71 170.18 0)
			(effects
				(font
					(size 1.27 1.27)
				)
				(justify left bottom)
				(hide yes)
			)
		)
		(property "Dielectric" "X5R"
			(at 217.17 170.18 0)
			(effects
				(font
					(size 1.27 1.27)
				)
				(justify left bottom)
				(hide yes)
			)
		)
		(pin "2"
		)
		(pin "1"
		)
		(instances
			(project "OCuLink to 10GbE adapter"
				(path ""
					(reference "C43")
					(unit 1)
				)
			)
		)
	)
	(symbol
		(lib_id "antmicropower:GND")
		(at 374.65 81.28 0)
		(unit 1)
		(exclude_from_sim no)
		(in_bom yes)
		(on_board yes)
		(dnp no)
		(property "Reference" "#PWR022"
			(at 383.54 83.82 0)
			(effects
				(font
					(size 1.27 1.27)
					(thickness 0.15)
				)
				(justify left bottom)
				(hide yes)
			)
		)
		(property "Value" "GND"
			(at 374.65 85.09 0)
			(effects
				(font
					(size 1.27 1.27)
					(thickness 0.15)
				)
			)
		)
		(property "Footprint" ""
			(at 383.54 88.9 0)
			(effects
				(font
					(size 1.27 1.27)
					(thickness 0.15)
				)
				(justify left bottom)
				(hide yes)
			)
		)
		(property "Datasheet" ""
			(at 383.54 93.98 0)
			(effects
				(font
					(size 1.27 1.27)
					(thickness 0.15)
				)
				(justify left bottom)
				(hide yes)
			)
		)
		(property "Description" ""
			(at 374.65 81.28 0)
			(effects
				(font
					(size 1.27 1.27)
				)
				(hide yes)
			)
		)
		(property "Author" "Antmicro"
			(at 383.54 88.9 0)
			(effects
				(font
					(size 1.27 1.27)
					(thickness 0.15)
				)
				(justify left bottom)
				(hide yes)
			)
		)
		(property "License" "Apache-2.0"
			(at 383.54 91.44 0)
			(effects
				(font
					(size 1.27 1.27)
					(thickness 0.15)
				)
				(justify left bottom)
				(hide yes)
			)
		)
		(pin "1"
		)
		(instances
			(project "OCuLink to 10GbE adapter"
				(path ""
					(reference "#PWR022")
					(unit 1)
				)
			)
		)
	)
	(symbol
		(lib_id "antmicropower:GND")
		(at 297.18 81.28 0)
		(unit 1)
		(exclude_from_sim no)
		(in_bom yes)
		(on_board yes)
		(dnp no)
		(property "Reference" "#PWR018"
			(at 306.07 83.82 0)
			(effects
				(font
					(size 1.27 1.27)
					(thickness 0.15)
				)
				(justify left bottom)
				(hide yes)
			)
		)
		(property "Value" "GND"
			(at 297.18 85.09 0)
			(effects
				(font
					(size 1.27 1.27)
					(thickness 0.15)
				)
			)
		)
		(property "Footprint" ""
			(at 306.07 88.9 0)
			(effects
				(font
					(size 1.27 1.27)
					(thickness 0.15)
				)
				(justify left bottom)
				(hide yes)
			)
		)
		(property "Datasheet" ""
			(at 306.07 93.98 0)
			(effects
				(font
					(size 1.27 1.27)
					(thickness 0.15)
				)
				(justify left bottom)
				(hide yes)
			)
		)
		(property "Description" ""
			(at 297.18 81.28 0)
			(effects
				(font
					(size 1.27 1.27)
				)
				(hide yes)
			)
		)
		(property "Author" "Antmicro"
			(at 306.07 88.9 0)
			(effects
				(font
					(size 1.27 1.27)
					(thickness 0.15)
				)
				(justify left bottom)
				(hide yes)
			)
		)
		(property "License" "Apache-2.0"
			(at 306.07 91.44 0)
			(effects
				(font
					(size 1.27 1.27)
					(thickness 0.15)
				)
				(justify left bottom)
				(hide yes)
			)
		)
		(pin "1"
		)
		(instances
			(project "OCuLink to 10GbE adapter"
				(path ""
					(reference "#PWR018")
					(unit 1)
				)
			)
		)
	)
	(symbol
		(lib_id "antmicropower:GND")
		(at 227.33 157.48 0)
		(unit 1)
		(exclude_from_sim no)
		(in_bom yes)
		(on_board yes)
		(dnp no)
		(property "Reference" "#PWR038"
			(at 236.22 160.02 0)
			(effects
				(font
					(size 1.27 1.27)
					(thickness 0.15)
				)
				(justify left bottom)
				(hide yes)
			)
		)
		(property "Value" "GND"
			(at 227.33 161.29 0)
			(effects
				(font
					(size 1.27 1.27)
					(thickness 0.15)
				)
			)
		)
		(property "Footprint" ""
			(at 236.22 165.1 0)
			(effects
				(font
					(size 1.27 1.27)
					(thickness 0.15)
				)
				(justify left bottom)
				(hide yes)
			)
		)
		(property "Datasheet" ""
			(at 236.22 170.18 0)
			(effects
				(font
					(size 1.27 1.27)
					(thickness 0.15)
				)
				(justify left bottom)
				(hide yes)
			)
		)
		(property "Description" ""
			(at 227.33 157.48 0)
			(effects
				(font
					(size 1.27 1.27)
				)
				(hide yes)
			)
		)
		(property "Author" "Antmicro"
			(at 236.22 165.1 0)
			(effects
				(font
					(size 1.27 1.27)
					(thickness 0.15)
				)
				(justify left bottom)
				(hide yes)
			)
		)
		(property "License" "Apache-2.0"
			(at 236.22 167.64 0)
			(effects
				(font
					(size 1.27 1.27)
					(thickness 0.15)
				)
				(justify left bottom)
				(hide yes)
			)
		)
		(pin "1"
		)
		(instances
			(project "OCuLink to 10GbE adapter"
				(path ""
					(reference "#PWR038")
					(unit 1)
				)
			)
		)
	)
	(symbol
		(lib_id "antmicropower:GND")
		(at 203.2 246.38 0)
		(mirror y)
		(unit 1)
		(exclude_from_sim no)
		(in_bom yes)
		(on_board yes)
		(dnp no)
		(property "Reference" "#PWR0315"
			(at 194.31 248.92 0)
			(effects
				(font
					(size 1.27 1.27)
					(thickness 0.15)
				)
				(justify left bottom)
				(hide yes)
			)
		)
		(property "Value" "GND"
			(at 203.2 250.19 0)
			(effects
				(font
					(size 1.27 1.27)
					(thickness 0.15)
				)
			)
		)
		(property "Footprint" ""
			(at 194.31 254 0)
			(effects
				(font
					(size 1.27 1.27)
					(thickness 0.15)
				)
				(justify left bottom)
				(hide yes)
			)
		)
		(property "Datasheet" ""
			(at 194.31 259.08 0)
			(effects
				(font
					(size 1.27 1.27)
					(thickness 0.15)
				)
				(justify left bottom)
				(hide yes)
			)
		)
		(property "Description" ""
			(at 203.2 246.38 0)
			(effects
				(font
					(size 1.27 1.27)
				)
				(hide yes)
			)
		)
		(property "Author" "Antmicro"
			(at 194.31 254 0)
			(effects
				(font
					(size 1.27 1.27)
					(thickness 0.15)
				)
				(justify left bottom)
				(hide yes)
			)
		)
		(property "License" "Apache-2.0"
			(at 194.31 256.54 0)
			(effects
				(font
					(size 1.27 1.27)
					(thickness 0.15)
				)
				(justify left bottom)
				(hide yes)
			)
		)
		(pin "1"
		)
		(instances
			(project "oculink-to-10gbe-adapter"
				(path ""
					(reference "#PWR0315")
					(unit 1)
				)
			)
		)
	)
	(symbol
		(lib_id "antmicropower:GND")
		(at 227.33 81.28 0)
		(unit 1)
		(exclude_from_sim no)
		(in_bom yes)
		(on_board yes)
		(dnp no)
		(property "Reference" "#PWR015"
			(at 236.22 83.82 0)
			(effects
				(font
					(size 1.27 1.27)
					(thickness 0.15)
				)
				(justify left bottom)
				(hide yes)
			)
		)
		(property "Value" "GND"
			(at 227.33 85.09 0)
			(effects
				(font
					(size 1.27 1.27)
					(thickness 0.15)
				)
			)
		)
		(property "Footprint" ""
			(at 236.22 88.9 0)
			(effects
				(font
					(size 1.27 1.27)
					(thickness 0.15)
				)
				(justify left bottom)
				(hide yes)
			)
		)
		(property "Datasheet" ""
			(at 236.22 93.98 0)
			(effects
				(font
					(size 1.27 1.27)
					(thickness 0.15)
				)
				(justify left bottom)
				(hide yes)
			)
		)
		(property "Description" ""
			(at 227.33 81.28 0)
			(effects
				(font
					(size 1.27 1.27)
				)
				(hide yes)
			)
		)
		(property "Author" "Antmicro"
			(at 236.22 88.9 0)
			(effects
				(font
					(size 1.27 1.27)
					(thickness 0.15)
				)
				(justify left bottom)
				(hide yes)
			)
		)
		(property "License" "Apache-2.0"
			(at 236.22 91.44 0)
			(effects
				(font
					(size 1.27 1.27)
					(thickness 0.15)
				)
				(justify left bottom)
				(hide yes)
			)
		)
		(pin "1"
		)
		(instances
			(project "OCuLink to 10GbE adapter"
				(path ""
					(reference "#PWR015")
					(unit 1)
				)
			)
		)
	)
	(symbol
		(lib_id "antmicroCapacitors0402:C_100n_0402")
		(at 237.49 152.4 270)
		(mirror x)
		(unit 1)
		(exclude_from_sim no)
		(in_bom yes)
		(on_board yes)
		(dnp no)
		(property "Reference" "C32"
			(at 235.712 148.59 90)
			(effects
				(font
					(size 1.27 1.27)
					(thickness 0.15)
				)
				(justify right)
			)
		)
		(property "Value" "C_100n_0402"
			(at 227.33 132.08 0)
			(effects
				(font
					(size 1.27 1.27)
					(thickness 0.15)
				)
				(justify left bottom)
				(hide yes)
			)
		)
		(property "Footprint" "antmicro-footprints:C_0402_1005Metric"
			(at 224.79 132.08 0)
			(effects
				(font
					(size 1.27 1.27)
					(thickness 0.15)
				)
				(justify left bottom)
				(hide yes)
			)
		)
		(property "Datasheet" "https://www.murata.com/products/productdetail?partno=GRM155R61H104KE14%23"
			(at 222.25 132.08 0)
			(effects
				(font
					(size 1.27 1.27)
					(thickness 0.15)
				)
				(justify left bottom)
				(hide yes)
			)
		)
		(property "Description" "SMD Multilayer Ceramic Capacitor, 0.1 µF, 50 V, 0402 [1005 Metric], ± 10%, X5R, GRM Series"
			(at 204.47 132.08 0)
			(effects
				(font
					(size 1.27 1.27)
				)
				(justify left bottom)
				(hide yes)
			)
		)
		(property "MPN" "GRM155R61H104KE14D"
			(at 219.71 132.08 0)
			(effects
				(font
					(size 1.27 1.27)
					(thickness 0.15)
				)
				(justify left bottom)
				(hide yes)
			)
		)
		(property "Manufacturer" "Murata"
			(at 217.17 132.08 0)
			(effects
				(font
					(size 1.27 1.27)
					(thickness 0.15)
				)
				(justify left bottom)
				(hide yes)
			)
		)
		(property "License" "Apache-2.0"
			(at 214.63 132.08 0)
			(effects
				(font
					(size 1.27 1.27)
					(thickness 0.15)
				)
				(justify left bottom)
				(hide yes)
			)
		)
		(property "Author" "Antmicro"
			(at 212.09 132.08 0)
			(effects
				(font
					(size 1.27 1.27)
					(thickness 0.15)
				)
				(justify left bottom)
				(hide yes)
			)
		)
		(property "Val" "100n"
			(at 235.712 151.13 90)
			(effects
				(font
					(size 1.27 1.27)
					(thickness 0.15)
				)
				(justify right)
			)
		)
		(property "Voltage" "50V"
			(at 209.55 132.08 0)
			(effects
				(font
					(size 1.27 1.27)
				)
				(justify left bottom)
				(hide yes)
			)
		)
		(property "Dielectric" "X5R"
			(at 207.01 132.08 0)
			(effects
				(font
					(size 1.27 1.27)
				)
				(justify left bottom)
				(hide yes)
			)
		)
		(pin "1"
		)
		(pin "2"
		)
		(instances
			(project "OCuLink to 10GbE adapter"
				(path ""
					(reference "C32")
					(unit 1)
				)
			)
		)
	)
	(symbol
		(lib_id "antmicroCapacitors0603:C_22u_16V_0603")
		(at 364.49 152.4 90)
		(unit 1)
		(exclude_from_sim no)
		(in_bom yes)
		(on_board yes)
		(dnp no)
		(property "Reference" "C207"
			(at 366.268 148.59 90)
			(effects
				(font
					(size 1.27 1.27)
					(thickness 0.15)
				)
				(justify right)
			)
		)
		(property "Value" "C_22u_16V_0603"
			(at 374.65 132.08 0)
			(effects
				(font
					(size 1.27 1.27)
					(thickness 0.15)
				)
				(justify left bottom)
				(hide yes)
			)
		)
		(property "Footprint" "antmicro-footprints:C_0603_1608Metric_EIA"
			(at 377.19 132.08 0)
			(effects
				(font
					(size 1.27 1.27)
					(thickness 0.15)
				)
				(justify left bottom)
				(hide yes)
			)
		)
		(property "Datasheet" "https://product.samsungsem.com/mlcc/CL10A226MO7JZN.do"
			(at 379.73 132.08 0)
			(effects
				(font
					(size 1.27 1.27)
					(thickness 0.15)
				)
				(justify left bottom)
				(hide yes)
			)
		)
		(property "Description" "SMD Multilayer Ceramic Capacitor"
			(at 364.49 152.4 0)
			(effects
				(font
					(size 1.27 1.27)
				)
				(hide yes)
			)
		)
		(property "MPN" "CL10A226MO7JZNC"
			(at 382.27 132.08 0)
			(effects
				(font
					(size 1.27 1.27)
					(thickness 0.15)
				)
				(justify left bottom)
				(hide yes)
			)
		)
		(property "Manufacturer" "Samsung Electro-Mechanics"
			(at 384.81 132.08 0)
			(effects
				(font
					(size 1.27 1.27)
					(thickness 0.15)
				)
				(justify left bottom)
				(hide yes)
			)
		)
		(property "License" "Apache-2.0"
			(at 387.35 132.08 0)
			(effects
				(font
					(size 1.27 1.27)
					(thickness 0.15)
				)
				(justify left bottom)
				(hide yes)
			)
		)
		(property "Author" "Antmicro"
			(at 389.89 132.08 0)
			(effects
				(font
					(size 1.27 1.27)
					(thickness 0.15)
				)
				(justify left bottom)
				(hide yes)
			)
		)
		(property "Val" "22u"
			(at 366.268 151.13 90)
			(effects
				(font
					(size 1.27 1.27)
					(thickness 0.15)
				)
				(justify right)
			)
		)
		(property "Voltage" "16V"
			(at 367.03 152.3935 90)
			(effects
				(font
					(size 1.27 1.27)
				)
				(justify right)
				(hide yes)
			)
		)
		(property "Dielectric" ""
			(at 394.97 132.08 0)
			(effects
				(font
					(size 1.27 1.27)
				)
				(justify left bottom)
				(hide yes)
			)
		)
		(property "Public" "False"
			(at 397.51 132.08 0)
			(effects
				(font
					(size 1.27 1.27)
				)
				(justify left bottom)
				(hide yes)
			)
		)
		(pin "2"
		)
		(pin "1"
		)
		(instances
			(project "OCuLink to 10GbE adapter"
				(path ""
					(reference "C207")
					(unit 1)
				)
			)
		)
	)
	(symbol
		(lib_id "antmicroResistors0402:R_20k_0402")
		(at 332.74 185.42 90)
		(unit 1)
		(exclude_from_sim no)
		(in_bom yes)
		(on_board yes)
		(dnp no)
		(property "Reference" "R29"
			(at 334.01 181.61 90)
			(effects
				(font
					(size 1.27 1.27)
					(thickness 0.15)
				)
				(justify right)
			)
		)
		(property "Value" "R_20k_0402"
			(at 345.44 165.1 0)
			(effects
				(font
					(size 1.27 1.27)
					(thickness 0.15)
				)
				(justify left bottom)
				(hide yes)
			)
		)
		(property "Footprint" "antmicro-footprints:R_0402_1005Metric"
			(at 347.98 165.1 0)
			(effects
				(font
					(size 1.27 1.27)
					(thickness 0.15)
				)
				(justify left bottom)
				(hide yes)
			)
		)
		(property "Datasheet" "https://www.bourns.com/docs/product-datasheets/cr.pdf"
			(at 350.52 165.1 0)
			(effects
				(font
					(size 1.27 1.27)
					(thickness 0.15)
				)
				(justify left bottom)
				(hide yes)
			)
		)
		(property "Description" "SMD Chip Resistor, 20 kohm, ± 1%, 62.5 mW, 0402 [1005 Metric], Thick Film, General Purpose"
			(at 363.22 165.1 0)
			(effects
				(font
					(size 1.27 1.27)
				)
				(justify left bottom)
				(hide yes)
			)
		)
		(property "MPN" "CR0402-FX-2002GLF"
			(at 353.06 165.1 0)
			(effects
				(font
					(size 1.27 1.27)
					(thickness 0.15)
				)
				(justify left bottom)
				(hide yes)
			)
		)
		(property "Manufacturer" "Bourns"
			(at 355.6 165.1 0)
			(effects
				(font
					(size 1.27 1.27)
					(thickness 0.15)
				)
				(justify left bottom)
				(hide yes)
			)
		)
		(property "License" "Apache-2.0"
			(at 358.14 165.1 0)
			(effects
				(font
					(size 1.27 1.27)
					(thickness 0.15)
				)
				(justify left bottom)
				(hide yes)
			)
		)
		(property "Author" "Antmicro"
			(at 360.68 165.1 0)
			(effects
				(font
					(size 1.27 1.27)
					(thickness 0.15)
				)
				(justify left bottom)
				(hide yes)
			)
		)
		(property "Val" "20k"
			(at 334.01 184.15 90)
			(effects
				(font
					(size 1.27 1.27)
					(thickness 0.15)
				)
				(justify right)
			)
		)
		(property "Tolerance" "1%"
			(at 342.9 165.1 0)
			(effects
				(font
					(size 1.27 1.27)
				)
				(justify left bottom)
				(hide yes)
			)
		)
		(pin "2"
		)
		(pin "1"
		)
		(instances
			(project "OCuLink to 10GbE adapter"
				(path ""
					(reference "R29")
					(unit 1)
				)
			)
		)
	)
	(symbol
		(lib_id "antmicropower:GND")
		(at 217.17 119.38 0)
		(unit 1)
		(exclude_from_sim no)
		(in_bom yes)
		(on_board yes)
		(dnp no)
		(property "Reference" "#PWR027"
			(at 226.06 121.92 0)
			(effects
				(font
					(size 1.27 1.27)
					(thickness 0.15)
				)
				(justify left bottom)
				(hide yes)
			)
		)
		(property "Value" "GND"
			(at 217.17 123.19 0)
			(effects
				(font
					(size 1.27 1.27)
					(thickness 0.15)
				)
			)
		)
		(property "Footprint" ""
			(at 226.06 127 0)
			(effects
				(font
					(size 1.27 1.27)
					(thickness 0.15)
				)
				(justify left bottom)
				(hide yes)
			)
		)
		(property "Datasheet" ""
			(at 226.06 132.08 0)
			(effects
				(font
					(size 1.27 1.27)
					(thickness 0.15)
				)
				(justify left bottom)
				(hide yes)
			)
		)
		(property "Description" ""
			(at 217.17 119.38 0)
			(effects
				(font
					(size 1.27 1.27)
				)
				(hide yes)
			)
		)
		(property "Author" "Antmicro"
			(at 226.06 127 0)
			(effects
				(font
					(size 1.27 1.27)
					(thickness 0.15)
				)
				(justify left bottom)
				(hide yes)
			)
		)
		(property "License" "Apache-2.0"
			(at 226.06 129.54 0)
			(effects
				(font
					(size 1.27 1.27)
					(thickness 0.15)
				)
				(justify left bottom)
				(hide yes)
			)
		)
		(pin "1"
		)
		(instances
			(project "OCuLink to 10GbE adapter"
				(path ""
					(reference "#PWR027")
					(unit 1)
				)
			)
		)
	)
	(symbol
		(lib_id "antmicroResistors0402:R_20k_0402")
		(at 332.74 147.32 90)
		(unit 1)
		(exclude_from_sim no)
		(in_bom yes)
		(on_board yes)
		(dnp no)
		(property "Reference" "R21"
			(at 334.01 143.51 90)
			(effects
				(font
					(size 1.27 1.27)
					(thickness 0.15)
				)
				(justify right)
			)
		)
		(property "Value" "R_20k_0402"
			(at 345.44 127 0)
			(effects
				(font
					(size 1.27 1.27)
					(thickness 0.15)
				)
				(justify left bottom)
				(hide yes)
			)
		)
		(property "Footprint" "antmicro-footprints:R_0402_1005Metric"
			(at 347.98 127 0)
			(effects
				(font
					(size 1.27 1.27)
					(thickness 0.15)
				)
				(justify left bottom)
				(hide yes)
			)
		)
		(property "Datasheet" "https://www.bourns.com/docs/product-datasheets/cr.pdf"
			(at 350.52 127 0)
			(effects
				(font
					(size 1.27 1.27)
					(thickness 0.15)
				)
				(justify left bottom)
				(hide yes)
			)
		)
		(property "Description" "SMD Chip Resistor, 20 kohm, ± 1%, 62.5 mW, 0402 [1005 Metric], Thick Film, General Purpose"
			(at 363.22 127 0)
			(effects
				(font
					(size 1.27 1.27)
				)
				(justify left bottom)
				(hide yes)
			)
		)
		(property "MPN" "CR0402-FX-2002GLF"
			(at 353.06 127 0)
			(effects
				(font
					(size 1.27 1.27)
					(thickness 0.15)
				)
				(justify left bottom)
				(hide yes)
			)
		)
		(property "Manufacturer" "Bourns"
			(at 355.6 127 0)
			(effects
				(font
					(size 1.27 1.27)
					(thickness 0.15)
				)
				(justify left bottom)
				(hide yes)
			)
		)
		(property "License" "Apache-2.0"
			(at 358.14 127 0)
			(effects
				(font
					(size 1.27 1.27)
					(thickness 0.15)
				)
				(justify left bottom)
				(hide yes)
			)
		)
		(property "Author" "Antmicro"
			(at 360.68 127 0)
			(effects
				(font
					(size 1.27 1.27)
					(thickness 0.15)
				)
				(justify left bottom)
				(hide yes)
			)
		)
		(property "Val" "20k"
			(at 334.01 146.05 90)
			(effects
				(font
					(size 1.27 1.27)
					(thickness 0.15)
				)
				(justify right)
			)
		)
		(property "Tolerance" "1%"
			(at 342.9 127 0)
			(effects
				(font
					(size 1.27 1.27)
				)
				(justify left bottom)
				(hide yes)
			)
		)
		(pin "2"
		)
		(pin "1"
		)
		(instances
			(project ""
				(path ""
					(reference "R21")
					(unit 1)
				)
			)
		)
	)
	(symbol
		(lib_id "antmicropower:GND")
		(at 374.65 43.18 0)
		(unit 1)
		(exclude_from_sim no)
		(in_bom yes)
		(on_board yes)
		(dnp no)
		(property "Reference" "#PWR012"
			(at 383.54 45.72 0)
			(effects
				(font
					(size 1.27 1.27)
					(thickness 0.15)
				)
				(justify left bottom)
				(hide yes)
			)
		)
		(property "Value" "GND"
			(at 374.65 46.99 0)
			(effects
				(font
					(size 1.27 1.27)
					(thickness 0.15)
				)
			)
		)
		(property "Footprint" ""
			(at 383.54 50.8 0)
			(effects
				(font
					(size 1.27 1.27)
					(thickness 0.15)
				)
				(justify left bottom)
				(hide yes)
			)
		)
		(property "Datasheet" ""
			(at 383.54 55.88 0)
			(effects
				(font
					(size 1.27 1.27)
					(thickness 0.15)
				)
				(justify left bottom)
				(hide yes)
			)
		)
		(property "Description" ""
			(at 374.65 43.18 0)
			(effects
				(font
					(size 1.27 1.27)
				)
				(hide yes)
			)
		)
		(property "Author" "Antmicro"
			(at 383.54 50.8 0)
			(effects
				(font
					(size 1.27 1.27)
					(thickness 0.15)
				)
				(justify left bottom)
				(hide yes)
			)
		)
		(property "License" "Apache-2.0"
			(at 383.54 53.34 0)
			(effects
				(font
					(size 1.27 1.27)
					(thickness 0.15)
				)
				(justify left bottom)
				(hide yes)
			)
		)
		(pin "1"
		)
		(instances
			(project "OCuLink to 10GbE adapter"
				(path ""
					(reference "#PWR012")
					(unit 1)
				)
			)
		)
	)
	(symbol
		(lib_id "antmicroDCDCConverters:TPS566231P")
		(at 276.86 139.7 0)
		(unit 1)
		(exclude_from_sim no)
		(in_bom yes)
		(on_board yes)
		(dnp no)
		(fields_autoplaced yes)
		(property "Reference" "U4"
			(at 285.75 133.35 0)
			(effects
				(font
					(size 1.27 1.27)
					(thickness 0.15)
				)
			)
		)
		(property "Value" "TPS566231P"
			(at 309.88 144.78 0)
			(effects
				(font
					(size 1.27 1.27)
					(thickness 0.15)
				)
				(justify left bottom)
				(hide yes)
			)
		)
		(property "Footprint" "antmicro-footprints:VQFN-HR-9_2x1.5mm"
			(at 309.88 147.32 0)
			(effects
				(font
					(size 1.27 1.27)
					(thickness 0.15)
				)
				(justify left bottom)
				(hide yes)
			)
		)
		(property "Datasheet" "https://www.ti.com/lit/ds/symlink/tps566231.pdf"
			(at 309.88 149.86 0)
			(effects
				(font
					(size 1.27 1.27)
					(thickness 0.15)
				)
				(justify left bottom)
				(hide yes)
			)
		)
		(property "Description" "Switching Voltage Regulators 3-V to 18-V, 6-A synchronous buck converter"
			(at 309.88 162.56 0)
			(effects
				(font
					(size 1.27 1.27)
				)
				(justify left bottom)
				(hide yes)
			)
		)
		(property "Manufacturer" "Texas Instruments"
			(at 309.88 152.4 0)
			(effects
				(font
					(size 1.27 1.27)
					(thickness 0.15)
				)
				(justify left bottom)
				(hide yes)
			)
		)
		(property "MPN" "TPS566231PRQFR"
			(at 285.75 135.89 0)
			(effects
				(font
					(size 1.27 1.27)
					(thickness 0.15)
				)
			)
		)
		(property "Author" "Antmicro"
			(at 309.88 157.48 0)
			(effects
				(font
					(size 1.27 1.27)
					(thickness 0.15)
				)
				(justify left bottom)
				(hide yes)
			)
		)
		(property "License" "Apache-2.0"
			(at 309.88 160.02 0)
			(effects
				(font
					(size 1.27 1.27)
					(thickness 0.15)
				)
				(justify left bottom)
				(hide yes)
			)
		)
		(pin "1"
		)
		(pin "2"
		)
		(pin "3"
		)
		(pin "9"
		)
		(pin "5"
		)
		(pin "6"
		)
		(pin "8"
		)
		(pin "4"
		)
		(pin "7"
		)
		(instances
			(project "OCuLink to 10GbE adapter"
				(path ""
					(reference "U4")
					(unit 1)
				)
			)
		)
	)
	(symbol
		(lib_id "antmicroTestPoints:TP_1mm_SMD")
		(at 391.16 228.6 0)
		(unit 1)
		(exclude_from_sim no)
		(in_bom no)
		(on_board yes)
		(dnp no)
		(fields_autoplaced yes)
		(property "Reference" "TP30"
			(at 396.24 228.6 0)
			(effects
				(font
					(size 1.27 1.27)
					(thickness 0.15)
				)
				(justify left)
			)
		)
		(property "Value" "TP_1mm_SMD"
			(at 406.4 236.22 0)
			(effects
				(font
					(size 1.27 1.27)
					(thickness 0.15)
				)
				(justify left bottom)
				(hide yes)
			)
		)
		(property "Footprint" "antmicro-footprints:TP_SMD_1mm"
			(at 406.4 238.76 0)
			(effects
				(font
					(size 1.27 1.27)
					(thickness 0.15)
				)
				(justify left bottom)
				(hide yes)
			)
		)
		(property "Datasheet" ""
			(at 408.94 241.3 0)
			(effects
				(font
					(size 1.27 1.27)
					(thickness 0.15)
				)
				(justify left bottom)
				(hide yes)
			)
		)
		(property "Description" "Test point 1mm SMD"
			(at 406.4 248.92 0)
			(effects
				(font
					(size 1.27 1.27)
				)
				(justify left bottom)
				(hide yes)
			)
		)
		(property "MPN" ""
			(at 391.16 228.6 0)
			(effects
				(font
					(size 1.27 1.27)
				)
				(hide yes)
			)
		)
		(property "Manufacturer" ""
			(at 391.16 228.6 0)
			(effects
				(font
					(size 1.27 1.27)
				)
				(hide yes)
			)
		)
		(property "Author" "Antmicro"
			(at 406.4 243.84 0)
			(effects
				(font
					(size 1.27 1.27)
					(thickness 0.15)
				)
				(justify left bottom)
				(hide yes)
			)
		)
		(property "License" "Apache-2.0"
			(at 406.4 246.38 0)
			(effects
				(font
					(size 1.27 1.27)
					(thickness 0.15)
				)
				(justify left bottom)
				(hide yes)
			)
		)
		(pin "1"
		)
		(instances
			(project "oculink-to-10gbe-adapter"
				(path ""
					(reference "TP30")
					(unit 1)
				)
			)
		)
	)
	(symbol
		(lib_id "antmicroTransistorsFETsMOSFETsSingle:2N7002_SOT-23-3")
		(at 339.09 240.03 0)
		(unit 1)
		(exclude_from_sim no)
		(in_bom yes)
		(on_board yes)
		(dnp no)
		(property "Reference" "Q1"
			(at 349.25 236.22 0)
			(effects
				(font
					(size 1.27 1.27)
					(thickness 0.15)
				)
				(justify left)
			)
		)
		(property "Value" "2N7002_SOT-23-3"
			(at 361.95 247.65 0)
			(effects
				(font
					(size 1.27 1.27)
					(thickness 0.15)
				)
				(justify left bottom)
				(hide yes)
			)
		)
		(property "Footprint" "antmicro-footprints:SOT-23-3"
			(at 361.95 250.19 0)
			(effects
				(font
					(size 1.27 1.27)
					(thickness 0.15)
				)
				(justify left bottom)
				(hide yes)
			)
		)
		(property "Datasheet" "https://www.onsemi.com/pub/Collateral/NDS7002A-D.PDF"
			(at 361.95 252.73 0)
			(effects
				(font
					(size 1.27 1.27)
					(thickness 0.15)
				)
				(justify left bottom)
				(hide yes)
			)
		)
		(property "Description" "Power MOSFET, N Channel, 60 V, 115 mA, 1.2 ohm, SOT-23, Surface Mount"
			(at 361.95 265.43 0)
			(effects
				(font
					(size 1.27 1.27)
				)
				(justify left bottom)
				(hide yes)
			)
		)
		(property "MPN" "2N7002"
			(at 349.25 238.76 0)
			(effects
				(font
					(size 1.27 1.27)
					(thickness 0.15)
				)
				(justify left)
			)
		)
		(property "Manufacturer" "ON Semiconductor"
			(at 361.95 257.81 0)
			(effects
				(font
					(size 1.27 1.27)
					(thickness 0.15)
				)
				(justify left bottom)
				(hide yes)
			)
		)
		(property "Author" "Antmicro"
			(at 361.95 260.35 0)
			(effects
				(font
					(size 1.27 1.27)
					(thickness 0.15)
				)
				(justify left bottom)
				(hide yes)
			)
		)
		(property "License" "Apache-2.0"
			(at 361.95 262.89 0)
			(effects
				(font
					(size 1.27 1.27)
					(thickness 0.15)
				)
				(justify left bottom)
				(hide yes)
			)
		)
		(pin "3"
		)
		(pin "2"
		)
		(pin "1"
		)
		(instances
			(project ""
				(path ""
					(reference "Q1")
					(unit 1)
				)
			)
		)
	)
	(symbol
		(lib_id "antmicropower:GND")
		(at 237.49 119.38 0)
		(unit 1)
		(exclude_from_sim no)
		(in_bom yes)
		(on_board yes)
		(dnp no)
		(property "Reference" "#PWR029"
			(at 246.38 121.92 0)
			(effects
				(font
					(size 1.27 1.27)
					(thickness 0.15)
				)
				(justify left bottom)
				(hide yes)
			)
		)
		(property "Value" "GND"
			(at 237.49 123.19 0)
			(effects
				(font
					(size 1.27 1.27)
					(thickness 0.15)
				)
			)
		)
		(property "Footprint" ""
			(at 246.38 127 0)
			(effects
				(font
					(size 1.27 1.27)
					(thickness 0.15)
				)
				(justify left bottom)
				(hide yes)
			)
		)
		(property "Datasheet" ""
			(at 246.38 132.08 0)
			(effects
				(font
					(size 1.27 1.27)
					(thickness 0.15)
				)
				(justify left bottom)
				(hide yes)
			)
		)
		(property "Description" ""
			(at 237.49 119.38 0)
			(effects
				(font
					(size 1.27 1.27)
				)
				(hide yes)
			)
		)
		(property "Author" "Antmicro"
			(at 246.38 127 0)
			(effects
				(font
					(size 1.27 1.27)
					(thickness 0.15)
				)
				(justify left bottom)
				(hide yes)
			)
		)
		(property "License" "Apache-2.0"
			(at 246.38 129.54 0)
			(effects
				(font
					(size 1.27 1.27)
					(thickness 0.15)
				)
				(justify left bottom)
				(hide yes)
			)
		)
		(pin "1"
		)
		(instances
			(project "OCuLink to 10GbE adapter"
				(path ""
					(reference "#PWR029")
					(unit 1)
				)
			)
		)
	)
	(symbol
		(lib_id "antmicroCapacitors0402:C_1u_25V_0402")
		(at 247.65 114.3 270)
		(mirror x)
		(unit 1)
		(exclude_from_sim no)
		(in_bom yes)
		(on_board yes)
		(dnp no)
		(property "Reference" "C24"
			(at 245.872 110.49 90)
			(effects
				(font
					(size 1.27 1.27)
					(thickness 0.15)
				)
				(justify right)
			)
		)
		(property "Value" "C_1u_25V_0402"
			(at 237.49 93.98 0)
			(effects
				(font
					(size 1.27 1.27)
					(thickness 0.15)
				)
				(justify left bottom)
				(hide yes)
			)
		)
		(property "Footprint" "antmicro-footprints:C_0402_1005Metric"
			(at 234.95 93.98 0)
			(effects
				(font
					(size 1.27 1.27)
					(thickness 0.15)
				)
				(justify left bottom)
				(hide yes)
			)
		)
		(property "Datasheet" "https://www.murata.com/products/productdetail?partno=GRM155R61E105KE11%23"
			(at 232.41 93.98 0)
			(effects
				(font
					(size 1.27 1.27)
					(thickness 0.15)
				)
				(justify left bottom)
				(hide yes)
			)
		)
		(property "Description" "SMD Multilayer Ceramic Capacitor, 1 µF, 25 V, 0402 [1005 Metric], ± 10%, X5R, GRM Series"
			(at 214.63 93.98 0)
			(effects
				(font
					(size 1.27 1.27)
				)
				(justify left bottom)
				(hide yes)
			)
		)
		(property "MPN" "GRM155R61E105KE11J"
			(at 229.87 93.98 0)
			(effects
				(font
					(size 1.27 1.27)
					(thickness 0.15)
				)
				(justify left bottom)
				(hide yes)
			)
		)
		(property "Manufacturer" "Murata"
			(at 227.33 93.98 0)
			(effects
				(font
					(size 1.27 1.27)
					(thickness 0.15)
				)
				(justify left bottom)
				(hide yes)
			)
		)
		(property "License" "Apache-2.0"
			(at 224.79 93.98 0)
			(effects
				(font
					(size 1.27 1.27)
					(thickness 0.15)
				)
				(justify left bottom)
				(hide yes)
			)
		)
		(property "Author" "Antmicro"
			(at 222.25 93.98 0)
			(effects
				(font
					(size 1.27 1.27)
					(thickness 0.15)
				)
				(justify left bottom)
				(hide yes)
			)
		)
		(property "Val" "1u"
			(at 245.872 113.03 90)
			(effects
				(font
					(size 1.27 1.27)
					(thickness 0.15)
				)
				(justify right)
			)
		)
		(property "Voltage" "25V"
			(at 219.71 93.98 0)
			(effects
				(font
					(size 1.27 1.27)
				)
				(justify left bottom)
				(hide yes)
			)
		)
		(property "Dielectric" "X5R"
			(at 217.17 93.98 0)
			(effects
				(font
					(size 1.27 1.27)
				)
				(justify left bottom)
				(hide yes)
			)
		)
		(pin "2"
		)
		(pin "1"
		)
		(instances
			(project "OCuLink to 10GbE adapter"
				(path ""
					(reference "C24")
					(unit 1)
				)
			)
		)
	)
	(symbol
		(lib_id "antmicroTestPoints:TP_0.75mm_SMD")
		(at 64.77 119.38 90)
		(unit 1)
		(exclude_from_sim no)
		(in_bom no)
		(on_board yes)
		(dnp no)
		(property "Reference" "TP24"
			(at 64.77 114.3 90)
			(effects
				(font
					(size 1.27 1.27)
					(thickness 0.15)
				)
			)
		)
		(property "Value" "TP_0.75mm_SMD"
			(at 68.58 109.22 0)
			(effects
				(font
					(size 1.27 1.27)
					(thickness 0.15)
				)
				(justify left bottom)
				(hide yes)
			)
		)
		(property "Footprint" "antmicro-footprints:TP_SMD_0.75mm"
			(at 71.12 109.22 0)
			(effects
				(font
					(size 1.27 1.27)
					(thickness 0.15)
				)
				(justify left bottom)
				(hide yes)
			)
		)
		(property "Datasheet" ""
			(at 77.47 101.6 0)
			(effects
				(font
					(size 1.27 1.27)
					(thickness 0.15)
				)
				(justify left bottom)
				(hide yes)
			)
		)
		(property "Description" "SMT test point"
			(at 64.77 119.38 0)
			(effects
				(font
					(size 1.27 1.27)
				)
				(hide yes)
			)
		)
		(property "MPN" ""
			(at 76.2 108.585 0)
			(effects
				(font
					(size 1.27 1.27)
					(thickness 0.15)
				)
				(justify left bottom)
				(hide yes)
			)
		)
		(property "Manufacturer" ""
			(at 71.12 108.585 0)
			(effects
				(font
					(size 1.27 1.27)
					(thickness 0.15)
				)
				(justify left bottom)
				(hide yes)
			)
		)
		(property "Author" "Antmicro"
			(at 73.66 109.22 0)
			(effects
				(font
					(size 1.27 1.27)
					(thickness 0.15)
				)
				(justify left bottom)
				(hide yes)
			)
		)
		(property "License" "Apache-2.0"
			(at 76.2 109.22 0)
			(effects
				(font
					(size 1.27 1.27)
					(thickness 0.15)
				)
				(justify left bottom)
				(hide yes)
			)
		)
		(pin "1"
		)
		(instances
			(project "OCuLink to 10GbE adapter"
				(path ""
					(reference "TP24")
					(unit 1)
				)
			)
		)
	)
	(symbol
		(lib_id "antmicroResistors0402:R_30k_0402")
		(at 332.74 80.01 90)
		(unit 1)
		(exclude_from_sim no)
		(in_bom yes)
		(on_board yes)
		(dnp no)
		(property "Reference" "R12"
			(at 334.01 76.2 90)
			(effects
				(font
					(size 1.27 1.27)
					(thickness 0.15)
				)
				(justify right)
			)
		)
		(property "Value" "R_30k_0402"
			(at 345.44 59.69 0)
			(effects
				(font
					(size 1.27 1.27)
					(thickness 0.15)
				)
				(justify left bottom)
				(hide yes)
			)
		)
		(property "Footprint" "antmicro-footprints:R_0402_1005Metric"
			(at 347.98 59.69 0)
			(effects
				(font
					(size 1.27 1.27)
					(thickness 0.15)
				)
				(justify left bottom)
				(hide yes)
			)
		)
		(property "Datasheet" "https://www.bourns.com/docs/product-datasheets/cr.pdf"
			(at 350.52 59.69 0)
			(effects
				(font
					(size 1.27 1.27)
					(thickness 0.15)
				)
				(justify left bottom)
				(hide yes)
			)
		)
		(property "Description" "SMD Chip Resistor, 30 kohm, ± 1%, 63 mW, 0402 [1005 Metric], Thick Film, General Purpose"
			(at 363.22 59.69 0)
			(effects
				(font
					(size 1.27 1.27)
				)
				(justify left bottom)
				(hide yes)
			)
		)
		(property "MPN" "CR0402-FX-3002GLF"
			(at 353.06 59.69 0)
			(effects
				(font
					(size 1.27 1.27)
					(thickness 0.15)
				)
				(justify left bottom)
				(hide yes)
			)
		)
		(property "Manufacturer" "Bourns"
			(at 355.6 59.69 0)
			(effects
				(font
					(size 1.27 1.27)
					(thickness 0.15)
				)
				(justify left bottom)
				(hide yes)
			)
		)
		(property "License" "Apache-2.0"
			(at 358.14 59.69 0)
			(effects
				(font
					(size 1.27 1.27)
					(thickness 0.15)
				)
				(justify left bottom)
				(hide yes)
			)
		)
		(property "Author" "Antmicro"
			(at 360.68 59.69 0)
			(effects
				(font
					(size 1.27 1.27)
					(thickness 0.15)
				)
				(justify left bottom)
				(hide yes)
			)
		)
		(property "Val" "30k"
			(at 334.01 78.74 90)
			(effects
				(font
					(size 1.27 1.27)
					(thickness 0.15)
				)
				(justify right)
			)
		)
		(property "Tolerance" "1%"
			(at 342.9 59.69 0)
			(effects
				(font
					(size 1.27 1.27)
				)
				(justify left bottom)
				(hide yes)
			)
		)
		(pin "2"
		)
		(pin "1"
		)
		(instances
			(project "OCuLink to 10GbE adapter"
				(path ""
					(reference "R12")
					(unit 1)
				)
			)
		)
	)
	(symbol
		(lib_id "antmicroCapacitors0402:C_33p_0402")
		(at 327.66 109.22 270)
		(mirror x)
		(unit 1)
		(exclude_from_sim no)
		(in_bom no)
		(on_board yes)
		(dnp yes)
		(property "Reference" "C20"
			(at 325.882 105.41 90)
			(effects
				(font
					(size 1.27 1.27)
					(thickness 0.15)
				)
				(justify right)
			)
		)
		(property "Value" "C_33p_0402"
			(at 317.5 88.9 0)
			(effects
				(font
					(size 1.27 1.27)
					(thickness 0.15)
				)
				(justify left bottom)
				(hide yes)
			)
		)
		(property "Footprint" "antmicro-footprints:C_0402_1005Metric"
			(at 314.96 88.9 0)
			(effects
				(font
					(size 1.27 1.27)
					(thickness 0.15)
				)
				(justify left bottom)
				(hide yes)
			)
		)
		(property "Datasheet" "https://spicat.kyocera-avx.com/product/mlcc/chartview/04025A330FAT2A/"
			(at 312.42 88.9 0)
			(effects
				(font
					(size 1.27 1.27)
					(thickness 0.15)
				)
				(justify left bottom)
				(hide yes)
			)
		)
		(property "Description" "SMD Multilayer Ceramic Capacitor, 33 pF, 50 V, 0402 [1005 Metric], ± 5%, C0G / NP0, MC"
			(at 294.64 88.9 0)
			(effects
				(font
					(size 1.27 1.27)
				)
				(justify left bottom)
				(hide yes)
			)
		)
		(property "MPN" "04025A330FAT2A"
			(at 309.88 88.9 0)
			(effects
				(font
					(size 1.27 1.27)
					(thickness 0.15)
				)
				(justify left bottom)
				(hide yes)
			)
		)
		(property "Manufacturer" "KYOCERA AVX"
			(at 307.34 88.9 0)
			(effects
				(font
					(size 1.27 1.27)
					(thickness 0.15)
				)
				(justify left bottom)
				(hide yes)
			)
		)
		(property "License" "Apache-2.0"
			(at 304.8 88.9 0)
			(effects
				(font
					(size 1.27 1.27)
					(thickness 0.15)
				)
				(justify left bottom)
				(hide yes)
			)
		)
		(property "Author" "Antmicro"
			(at 302.26 88.9 0)
			(effects
				(font
					(size 1.27 1.27)
					(thickness 0.15)
				)
				(justify left bottom)
				(hide yes)
			)
		)
		(property "Val" "33p"
			(at 325.882 107.95 90)
			(effects
				(font
					(size 1.27 1.27)
					(thickness 0.15)
				)
				(justify right)
			)
		)
		(property "Voltage" ""
			(at 299.72 88.9 0)
			(effects
				(font
					(size 1.27 1.27)
				)
				(justify left bottom)
				(hide yes)
			)
		)
		(property "Dielectric" ""
			(at 297.18 88.9 0)
			(effects
				(font
					(size 1.27 1.27)
				)
				(justify left bottom)
				(hide yes)
			)
		)
		(pin "2"
		)
		(pin "1"
		)
		(instances
			(project "OCuLink to 10GbE adapter"
				(path ""
					(reference "C20")
					(unit 1)
				)
			)
		)
	)
	(symbol
		(lib_id "antmicropower:GND")
		(at 332.74 43.18 0)
		(unit 1)
		(exclude_from_sim no)
		(in_bom yes)
		(on_board yes)
		(dnp no)
		(property "Reference" "#PWR09"
			(at 341.63 45.72 0)
			(effects
				(font
					(size 1.27 1.27)
					(thickness 0.15)
				)
				(justify left bottom)
				(hide yes)
			)
		)
		(property "Value" "GND"
			(at 332.74 46.99 0)
			(effects
				(font
					(size 1.27 1.27)
					(thickness 0.15)
				)
			)
		)
		(property "Footprint" ""
			(at 341.63 50.8 0)
			(effects
				(font
					(size 1.27 1.27)
					(thickness 0.15)
				)
				(justify left bottom)
				(hide yes)
			)
		)
		(property "Datasheet" ""
			(at 341.63 55.88 0)
			(effects
				(font
					(size 1.27 1.27)
					(thickness 0.15)
				)
				(justify left bottom)
				(hide yes)
			)
		)
		(property "Description" ""
			(at 332.74 43.18 0)
			(effects
				(font
					(size 1.27 1.27)
				)
				(hide yes)
			)
		)
		(property "Author" "Antmicro"
			(at 341.63 50.8 0)
			(effects
				(font
					(size 1.27 1.27)
					(thickness 0.15)
				)
				(justify left bottom)
				(hide yes)
			)
		)
		(property "License" "Apache-2.0"
			(at 341.63 53.34 0)
			(effects
				(font
					(size 1.27 1.27)
					(thickness 0.15)
				)
				(justify left bottom)
				(hide yes)
			)
		)
		(pin "1"
		)
		(instances
			(project "OCuLink to 10GbE adapter"
				(path ""
					(reference "#PWR09")
					(unit 1)
				)
			)
		)
	)
	(symbol
		(lib_id "antmicropower:GND")
		(at 81.28 172.72 0)
		(unit 1)
		(exclude_from_sim no)
		(in_bom yes)
		(on_board yes)
		(dnp no)
		(property "Reference" "#PWR049"
			(at 90.17 175.26 0)
			(effects
				(font
					(size 1.27 1.27)
					(thickness 0.15)
				)
				(justify left bottom)
				(hide yes)
			)
		)
		(property "Value" "GND"
			(at 81.28 176.53 0)
			(effects
				(font
					(size 1.27 1.27)
					(thickness 0.15)
				)
			)
		)
		(property "Footprint" ""
			(at 90.17 180.34 0)
			(effects
				(font
					(size 1.27 1.27)
					(thickness 0.15)
				)
				(justify left bottom)
				(hide yes)
			)
		)
		(property "Datasheet" ""
			(at 90.17 185.42 0)
			(effects
				(font
					(size 1.27 1.27)
					(thickness 0.15)
				)
				(justify left bottom)
				(hide yes)
			)
		)
		(property "Description" ""
			(at 81.28 172.72 0)
			(effects
				(font
					(size 1.27 1.27)
				)
				(hide yes)
			)
		)
		(property "Author" "Antmicro"
			(at 90.17 180.34 0)
			(effects
				(font
					(size 1.27 1.27)
					(thickness 0.15)
				)
				(justify left bottom)
				(hide yes)
			)
		)
		(property "License" "Apache-2.0"
			(at 90.17 182.88 0)
			(effects
				(font
					(size 1.27 1.27)
					(thickness 0.15)
				)
				(justify left bottom)
				(hide yes)
			)
		)
		(pin "1"
		)
		(instances
			(project "OCuLink to 10GbE adapter"
				(path ""
					(reference "#PWR049")
					(unit 1)
				)
			)
		)
	)
	(symbol
		(lib_id "antmicroCapacitors0402:C_100n_0402")
		(at 237.49 190.5 270)
		(mirror x)
		(unit 1)
		(exclude_from_sim no)
		(in_bom yes)
		(on_board yes)
		(dnp no)
		(property "Reference" "C42"
			(at 235.712 186.69 90)
			(effects
				(font
					(size 1.27 1.27)
					(thickness 0.15)
				)
				(justify right)
			)
		)
		(property "Value" "C_100n_0402"
			(at 227.33 170.18 0)
			(effects
				(font
					(size 1.27 1.27)
					(thickness 0.15)
				)
				(justify left bottom)
				(hide yes)
			)
		)
		(property "Footprint" "antmicro-footprints:C_0402_1005Metric"
			(at 224.79 170.18 0)
			(effects
				(font
					(size 1.27 1.27)
					(thickness 0.15)
				)
				(justify left bottom)
				(hide yes)
			)
		)
		(property "Datasheet" "https://www.murata.com/products/productdetail?partno=GRM155R61H104KE14%23"
			(at 222.25 170.18 0)
			(effects
				(font
					(size 1.27 1.27)
					(thickness 0.15)
				)
				(justify left bottom)
				(hide yes)
			)
		)
		(property "Description" "SMD Multilayer Ceramic Capacitor, 0.1 µF, 50 V, 0402 [1005 Metric], ± 10%, X5R, GRM Series"
			(at 204.47 170.18 0)
			(effects
				(font
					(size 1.27 1.27)
				)
				(justify left bottom)
				(hide yes)
			)
		)
		(property "MPN" "GRM155R61H104KE14D"
			(at 219.71 170.18 0)
			(effects
				(font
					(size 1.27 1.27)
					(thickness 0.15)
				)
				(justify left bottom)
				(hide yes)
			)
		)
		(property "Manufacturer" "Murata"
			(at 217.17 170.18 0)
			(effects
				(font
					(size 1.27 1.27)
					(thickness 0.15)
				)
				(justify left bottom)
				(hide yes)
			)
		)
		(property "License" "Apache-2.0"
			(at 214.63 170.18 0)
			(effects
				(font
					(size 1.27 1.27)
					(thickness 0.15)
				)
				(justify left bottom)
				(hide yes)
			)
		)
		(property "Author" "Antmicro"
			(at 212.09 170.18 0)
			(effects
				(font
					(size 1.27 1.27)
					(thickness 0.15)
				)
				(justify left bottom)
				(hide yes)
			)
		)
		(property "Val" "100n"
			(at 235.712 189.23 90)
			(effects
				(font
					(size 1.27 1.27)
					(thickness 0.15)
				)
				(justify right)
			)
		)
		(property "Voltage" "50V"
			(at 209.55 170.18 0)
			(effects
				(font
					(size 1.27 1.27)
				)
				(justify left bottom)
				(hide yes)
			)
		)
		(property "Dielectric" "X5R"
			(at 207.01 170.18 0)
			(effects
				(font
					(size 1.27 1.27)
				)
				(justify left bottom)
				(hide yes)
			)
		)
		(pin "1"
		)
		(pin "2"
		)
		(instances
			(project "OCuLink to 10GbE adapter"
				(path ""
					(reference "C42")
					(unit 1)
				)
			)
		)
	)
	(symbol
		(lib_id "antmicropower:GND")
		(at 364.49 195.58 0)
		(unit 1)
		(exclude_from_sim no)
		(in_bom yes)
		(on_board yes)
		(dnp no)
		(property "Reference" "#PWR0337"
			(at 373.38 198.12 0)
			(effects
				(font
					(size 1.27 1.27)
					(thickness 0.15)
				)
				(justify left bottom)
				(hide yes)
			)
		)
		(property "Value" "GND"
			(at 364.49 199.39 0)
			(effects
				(font
					(size 1.27 1.27)
					(thickness 0.15)
				)
			)
		)
		(property "Footprint" ""
			(at 373.38 203.2 0)
			(effects
				(font
					(size 1.27 1.27)
					(thickness 0.15)
				)
				(justify left bottom)
				(hide yes)
			)
		)
		(property "Datasheet" ""
			(at 373.38 208.28 0)
			(effects
				(font
					(size 1.27 1.27)
					(thickness 0.15)
				)
				(justify left bottom)
				(hide yes)
			)
		)
		(property "Description" ""
			(at 364.49 195.58 0)
			(effects
				(font
					(size 1.27 1.27)
				)
				(hide yes)
			)
		)
		(property "Author" "Antmicro"
			(at 373.38 203.2 0)
			(effects
				(font
					(size 1.27 1.27)
					(thickness 0.15)
				)
				(justify left bottom)
				(hide yes)
			)
		)
		(property "License" "Apache-2.0"
			(at 373.38 205.74 0)
			(effects
				(font
					(size 1.27 1.27)
					(thickness 0.15)
				)
				(justify left bottom)
				(hide yes)
			)
		)
		(pin "1"
		)
		(instances
			(project "OCuLink to 10GbE adapter"
				(path ""
					(reference "#PWR0337")
					(unit 1)
				)
			)
		)
	)
	(symbol
		(lib_id "antmicropower:GND")
		(at 91.44 172.72 0)
		(unit 1)
		(exclude_from_sim no)
		(in_bom yes)
		(on_board yes)
		(dnp no)
		(property "Reference" "#PWR050"
			(at 100.33 175.26 0)
			(effects
				(font
					(size 1.27 1.27)
					(thickness 0.15)
				)
				(justify left bottom)
				(hide yes)
			)
		)
		(property "Value" "GND"
			(at 91.44 176.53 0)
			(effects
				(font
					(size 1.27 1.27)
					(thickness 0.15)
				)
			)
		)
		(property "Footprint" ""
			(at 100.33 180.34 0)
			(effects
				(font
					(size 1.27 1.27)
					(thickness 0.15)
				)
				(justify left bottom)
				(hide yes)
			)
		)
		(property "Datasheet" ""
			(at 100.33 185.42 0)
			(effects
				(font
					(size 1.27 1.27)
					(thickness 0.15)
				)
				(justify left bottom)
				(hide yes)
			)
		)
		(property "Description" ""
			(at 91.44 172.72 0)
			(effects
				(font
					(size 1.27 1.27)
				)
				(hide yes)
			)
		)
		(property "Author" "Antmicro"
			(at 100.33 180.34 0)
			(effects
				(font
					(size 1.27 1.27)
					(thickness 0.15)
				)
				(justify left bottom)
				(hide yes)
			)
		)
		(property "License" "Apache-2.0"
			(at 100.33 182.88 0)
			(effects
				(font
					(size 1.27 1.27)
					(thickness 0.15)
				)
				(justify left bottom)
				(hide yes)
			)
		)
		(pin "1"
		)
		(instances
			(project "OCuLink to 10GbE adapter"
				(path ""
					(reference "#PWR050")
					(unit 1)
				)
			)
		)
	)
	(symbol
		(lib_id "antmicropower:GND")
		(at 67.31 172.72 0)
		(unit 1)
		(exclude_from_sim no)
		(in_bom yes)
		(on_board yes)
		(dnp no)
		(property "Reference" "#PWR047"
			(at 76.2 175.26 0)
			(effects
				(font
					(size 1.27 1.27)
					(thickness 0.15)
				)
				(justify left bottom)
				(hide yes)
			)
		)
		(property "Value" "GND"
			(at 67.31 176.53 0)
			(effects
				(font
					(size 1.27 1.27)
					(thickness 0.15)
				)
			)
		)
		(property "Footprint" ""
			(at 76.2 180.34 0)
			(effects
				(font
					(size 1.27 1.27)
					(thickness 0.15)
				)
				(justify left bottom)
				(hide yes)
			)
		)
		(property "Datasheet" ""
			(at 76.2 185.42 0)
			(effects
				(font
					(size 1.27 1.27)
					(thickness 0.15)
				)
				(justify left bottom)
				(hide yes)
			)
		)
		(property "Description" ""
			(at 67.31 172.72 0)
			(effects
				(font
					(size 1.27 1.27)
				)
				(hide yes)
			)
		)
		(property "Author" "Antmicro"
			(at 76.2 180.34 0)
			(effects
				(font
					(size 1.27 1.27)
					(thickness 0.15)
				)
				(justify left bottom)
				(hide yes)
			)
		)
		(property "License" "Apache-2.0"
			(at 76.2 182.88 0)
			(effects
				(font
					(size 1.27 1.27)
					(thickness 0.15)
				)
				(justify left bottom)
				(hide yes)
			)
		)
		(pin "1"
		)
		(instances
			(project "OCuLink to 10GbE adapter"
				(path ""
					(reference "#PWR047")
					(unit 1)
				)
			)
		)
	)
	(symbol
		(lib_id "antmicroTestPoints:TP_0.75mm_SMD")
		(at 358.14 24.13 90)
		(unit 1)
		(exclude_from_sim no)
		(in_bom no)
		(on_board yes)
		(dnp no)
		(property "Reference" "TP21"
			(at 358.14 19.05 90)
			(effects
				(font
					(size 1.27 1.27)
					(thickness 0.15)
				)
			)
		)
		(property "Value" "TP_0.75mm_SMD"
			(at 361.95 13.97 0)
			(effects
				(font
					(size 1.27 1.27)
					(thickness 0.15)
				)
				(justify left bottom)
				(hide yes)
			)
		)
		(property "Footprint" "antmicro-footprints:TP_SMD_0.75mm"
			(at 364.49 13.97 0)
			(effects
				(font
					(size 1.27 1.27)
					(thickness 0.15)
				)
				(justify left bottom)
				(hide yes)
			)
		)
		(property "Datasheet" ""
			(at 370.84 6.35 0)
			(effects
				(font
					(size 1.27 1.27)
					(thickness 0.15)
				)
				(justify left bottom)
				(hide yes)
			)
		)
		(property "Description" "SMT test point"
			(at 358.14 24.13 0)
			(effects
				(font
					(size 1.27 1.27)
				)
				(hide yes)
			)
		)
		(property "MPN" ""
			(at 369.57 13.335 0)
			(effects
				(font
					(size 1.27 1.27)
					(thickness 0.15)
				)
				(justify left bottom)
				(hide yes)
			)
		)
		(property "Manufacturer" ""
			(at 364.49 13.335 0)
			(effects
				(font
					(size 1.27 1.27)
					(thickness 0.15)
				)
				(justify left bottom)
				(hide yes)
			)
		)
		(property "Author" "Antmicro"
			(at 367.03 13.97 0)
			(effects
				(font
					(size 1.27 1.27)
					(thickness 0.15)
				)
				(justify left bottom)
				(hide yes)
			)
		)
		(property "License" "Apache-2.0"
			(at 369.57 13.97 0)
			(effects
				(font
					(size 1.27 1.27)
					(thickness 0.15)
				)
				(justify left bottom)
				(hide yes)
			)
		)
		(pin "1"
		)
		(instances
			(project "OCuLink to 10GbE adapter"
				(path ""
					(reference "TP21")
					(unit 1)
				)
			)
		)
	)
	(symbol
		(lib_id "antmicroTestPoints:TP_0.75mm_SMD")
		(at 358.14 138.43 90)
		(unit 1)
		(exclude_from_sim no)
		(in_bom no)
		(on_board yes)
		(dnp no)
		(property "Reference" "TP18"
			(at 358.14 133.35 90)
			(effects
				(font
					(size 1.27 1.27)
					(thickness 0.15)
				)
			)
		)
		(property "Value" "TP_0.75mm_SMD"
			(at 361.95 128.27 0)
			(effects
				(font
					(size 1.27 1.27)
					(thickness 0.15)
				)
				(justify left bottom)
				(hide yes)
			)
		)
		(property "Footprint" "antmicro-footprints:TP_SMD_0.75mm"
			(at 364.49 128.27 0)
			(effects
				(font
					(size 1.27 1.27)
					(thickness 0.15)
				)
				(justify left bottom)
				(hide yes)
			)
		)
		(property "Datasheet" ""
			(at 370.84 120.65 0)
			(effects
				(font
					(size 1.27 1.27)
					(thickness 0.15)
				)
				(justify left bottom)
				(hide yes)
			)
		)
		(property "Description" "SMT test point"
			(at 358.14 138.43 0)
			(effects
				(font
					(size 1.27 1.27)
				)
				(hide yes)
			)
		)
		(property "MPN" ""
			(at 369.57 127.635 0)
			(effects
				(font
					(size 1.27 1.27)
					(thickness 0.15)
				)
				(justify left bottom)
				(hide yes)
			)
		)
		(property "Manufacturer" ""
			(at 364.49 127.635 0)
			(effects
				(font
					(size 1.27 1.27)
					(thickness 0.15)
				)
				(justify left bottom)
				(hide yes)
			)
		)
		(property "Author" "Antmicro"
			(at 367.03 128.27 0)
			(effects
				(font
					(size 1.27 1.27)
					(thickness 0.15)
				)
				(justify left bottom)
				(hide yes)
			)
		)
		(property "License" "Apache-2.0"
			(at 369.57 128.27 0)
			(effects
				(font
					(size 1.27 1.27)
					(thickness 0.15)
				)
				(justify left bottom)
				(hide yes)
			)
		)
		(pin "1"
		)
		(instances
			(project "OCuLink to 10GbE adapter"
				(path ""
					(reference "TP18")
					(unit 1)
				)
			)
		)
	)
	(symbol
		(lib_id "antmicroLEDIndicationDiscrete:LED_G_0603_LG_L29K-G2J1-24-Z")
		(at 203.2 223.52 90)
		(unit 1)
		(exclude_from_sim no)
		(in_bom yes)
		(on_board yes)
		(dnp no)
		(property "Reference" "D17"
			(at 204.47 219.71 90)
			(effects
				(font
					(size 1.27 1.27)
					(thickness 0.15)
				)
				(justify right)
			)
		)
		(property "Value" "LED_G_0603_LG_L29K-G2J1-24-Z"
			(at 210.82 203.2 0)
			(effects
				(font
					(size 1.27 1.27)
					(thickness 0.15)
				)
				(justify left bottom)
				(hide yes)
			)
		)
		(property "Footprint" "antmicro-footprints:LED_0603_1608Metric_G"
			(at 213.36 203.2 0)
			(effects
				(font
					(size 1.27 1.27)
					(thickness 0.15)
				)
				(justify left bottom)
				(hide yes)
			)
		)
		(property "Datasheet" "https://look.ams-osram.com/m/19ee86b3ae0ee95b/original/LG-L29K.pdf"
			(at 215.9 203.2 0)
			(effects
				(font
					(size 1.27 1.27)
					(thickness 0.15)
				)
				(justify left bottom)
				(hide yes)
			)
		)
		(property "Description" "LED, Green, SMD, 0603, 20 mA, 1.7 V, 570 nm"
			(at 203.2 223.52 0)
			(effects
				(font
					(size 1.27 1.27)
				)
				(hide yes)
			)
		)
		(property "MPN" "LG L29K-G2J1-24-Z"
			(at 218.44 203.2 0)
			(effects
				(font
					(size 1.27 1.27)
					(thickness 0.15)
				)
				(justify left bottom)
				(hide yes)
			)
		)
		(property "Manufacturer" "OSRAM"
			(at 220.98 203.2 0)
			(effects
				(font
					(size 1.27 1.27)
					(thickness 0.15)
				)
				(justify left bottom)
				(hide yes)
			)
		)
		(property "Color" "Green"
			(at 204.47 222.2499 90)
			(effects
				(font
					(size 1.27 1.27)
				)
				(justify right)
			)
		)
		(property "Author" "Antmicro"
			(at 223.52 203.2 0)
			(effects
				(font
					(size 1.27 1.27)
					(thickness 0.15)
				)
				(justify left bottom)
				(hide yes)
			)
		)
		(property "License" "Apache-2.0"
			(at 226.06 203.2 0)
			(effects
				(font
					(size 1.27 1.27)
					(thickness 0.15)
				)
				(justify left bottom)
				(hide yes)
			)
		)
		(pin "2"
		)
		(pin "1"
		)
		(instances
			(project "oculink-to-10gbe-adapter"
				(path ""
					(reference "D17")
					(unit 1)
				)
			)
		)
	)
	(symbol
		(lib_id "antmicropower:GND")
		(at 254 246.38 0)
		(mirror y)
		(unit 1)
		(exclude_from_sim no)
		(in_bom yes)
		(on_board yes)
		(dnp no)
		(property "Reference" "#PWR0350"
			(at 245.11 248.92 0)
			(effects
				(font
					(size 1.27 1.27)
					(thickness 0.15)
				)
				(justify left bottom)
				(hide yes)
			)
		)
		(property "Value" "GND"
			(at 254 250.19 0)
			(effects
				(font
					(size 1.27 1.27)
					(thickness 0.15)
				)
			)
		)
		(property "Footprint" ""
			(at 245.11 254 0)
			(effects
				(font
					(size 1.27 1.27)
					(thickness 0.15)
				)
				(justify left bottom)
				(hide yes)
			)
		)
		(property "Datasheet" ""
			(at 245.11 259.08 0)
			(effects
				(font
					(size 1.27 1.27)
					(thickness 0.15)
				)
				(justify left bottom)
				(hide yes)
			)
		)
		(property "Description" ""
			(at 254 246.38 0)
			(effects
				(font
					(size 1.27 1.27)
				)
				(hide yes)
			)
		)
		(property "Author" "Antmicro"
			(at 245.11 254 0)
			(effects
				(font
					(size 1.27 1.27)
					(thickness 0.15)
				)
				(justify left bottom)
				(hide yes)
			)
		)
		(property "License" "Apache-2.0"
			(at 245.11 256.54 0)
			(effects
				(font
					(size 1.27 1.27)
					(thickness 0.15)
				)
				(justify left bottom)
				(hide yes)
			)
		)
		(pin "1"
		)
		(instances
			(project "oculink-to-10gbe-adapter"
				(path ""
					(reference "#PWR0350")
					(unit 1)
				)
			)
		)
	)
	(symbol
		(lib_id "antmicropower:+1V0")
		(at 400.05 137.16 0)
		(unit 1)
		(exclude_from_sim no)
		(in_bom yes)
		(on_board yes)
		(dnp no)
		(property "Reference" "#PWR036"
			(at 400.05 140.97 0)
			(effects
				(font
					(size 1.27 1.27)
				)
				(hide yes)
			)
		)
		(property "Value" "+1V0"
			(at 400.05 133.35 0)
			(effects
				(font
					(size 1.27 1.27)
				)
			)
		)
		(property "Footprint" ""
			(at 400.05 137.16 0)
			(effects
				(font
					(size 1.27 1.27)
				)
				(hide yes)
			)
		)
		(property "Datasheet" ""
			(at 400.05 137.16 0)
			(effects
				(font
					(size 1.27 1.27)
				)
				(hide yes)
			)
		)
		(property "Description" ""
			(at 400.05 137.16 0)
			(effects
				(font
					(size 1.27 1.27)
				)
				(hide yes)
			)
		)
		(pin "1"
		)
		(instances
			(project "OCuLink to 10GbE adapter"
				(path ""
					(reference "#PWR036")
					(unit 1)
				)
			)
		)
	)
	(symbol
		(lib_id "antmicroResistors0402:R_30k_0402")
		(at 332.74 156.21 90)
		(unit 1)
		(exclude_from_sim no)
		(in_bom yes)
		(on_board yes)
		(dnp no)
		(property "Reference" "R26"
			(at 334.01 152.4 90)
			(effects
				(font
					(size 1.27 1.27)
					(thickness 0.15)
				)
				(justify right)
			)
		)
		(property "Value" "R_30k_0402"
			(at 345.44 135.89 0)
			(effects
				(font
					(size 1.27 1.27)
					(thickness 0.15)
				)
				(justify left bottom)
				(hide yes)
			)
		)
		(property "Footprint" "antmicro-footprints:R_0402_1005Metric"
			(at 347.98 135.89 0)
			(effects
				(font
					(size 1.27 1.27)
					(thickness 0.15)
				)
				(justify left bottom)
				(hide yes)
			)
		)
		(property "Datasheet" "https://www.bourns.com/docs/product-datasheets/cr.pdf"
			(at 350.52 135.89 0)
			(effects
				(font
					(size 1.27 1.27)
					(thickness 0.15)
				)
				(justify left bottom)
				(hide yes)
			)
		)
		(property "Description" "SMD Chip Resistor, 30 kohm, ± 1%, 63 mW, 0402 [1005 Metric], Thick Film, General Purpose"
			(at 363.22 135.89 0)
			(effects
				(font
					(size 1.27 1.27)
				)
				(justify left bottom)
				(hide yes)
			)
		)
		(property "MPN" "CR0402-FX-3002GLF"
			(at 353.06 135.89 0)
			(effects
				(font
					(size 1.27 1.27)
					(thickness 0.15)
				)
				(justify left bottom)
				(hide yes)
			)
		)
		(property "Manufacturer" "Bourns"
			(at 355.6 135.89 0)
			(effects
				(font
					(size 1.27 1.27)
					(thickness 0.15)
				)
				(justify left bottom)
				(hide yes)
			)
		)
		(property "License" "Apache-2.0"
			(at 358.14 135.89 0)
			(effects
				(font
					(size 1.27 1.27)
					(thickness 0.15)
				)
				(justify left bottom)
				(hide yes)
			)
		)
		(property "Author" "Antmicro"
			(at 360.68 135.89 0)
			(effects
				(font
					(size 1.27 1.27)
					(thickness 0.15)
				)
				(justify left bottom)
				(hide yes)
			)
		)
		(property "Val" "30k"
			(at 334.01 154.94 90)
			(effects
				(font
					(size 1.27 1.27)
					(thickness 0.15)
				)
				(justify right)
			)
		)
		(property "Tolerance" "1%"
			(at 342.9 135.89 0)
			(effects
				(font
					(size 1.27 1.27)
				)
				(justify left bottom)
				(hide yes)
			)
		)
		(pin "2"
		)
		(pin "1"
		)
		(instances
			(project ""
				(path ""
					(reference "R26")
					(unit 1)
				)
			)
		)
	)
	(symbol
		(lib_id "antmicroDCDCConverters:TPS566231P")
		(at 276.86 101.6 0)
		(unit 1)
		(exclude_from_sim no)
		(in_bom yes)
		(on_board yes)
		(dnp no)
		(fields_autoplaced yes)
		(property "Reference" "U3"
			(at 285.75 95.25 0)
			(effects
				(font
					(size 1.27 1.27)
					(thickness 0.15)
				)
			)
		)
		(property "Value" "TPS566231P"
			(at 309.88 106.68 0)
			(effects
				(font
					(size 1.27 1.27)
					(thickness 0.15)
				)
				(justify left bottom)
				(hide yes)
			)
		)
		(property "Footprint" "antmicro-footprints:VQFN-HR-9_2x1.5mm"
			(at 309.88 109.22 0)
			(effects
				(font
					(size 1.27 1.27)
					(thickness 0.15)
				)
				(justify left bottom)
				(hide yes)
			)
		)
		(property "Datasheet" "https://www.ti.com/lit/ds/symlink/tps566231.pdf"
			(at 309.88 111.76 0)
			(effects
				(font
					(size 1.27 1.27)
					(thickness 0.15)
				)
				(justify left bottom)
				(hide yes)
			)
		)
		(property "Description" "Switching Voltage Regulators 3-V to 18-V, 6-A synchronous buck converter"
			(at 309.88 124.46 0)
			(effects
				(font
					(size 1.27 1.27)
				)
				(justify left bottom)
				(hide yes)
			)
		)
		(property "Manufacturer" "Texas Instruments"
			(at 309.88 114.3 0)
			(effects
				(font
					(size 1.27 1.27)
					(thickness 0.15)
				)
				(justify left bottom)
				(hide yes)
			)
		)
		(property "MPN" "TPS566231PRQFR"
			(at 285.75 97.79 0)
			(effects
				(font
					(size 1.27 1.27)
					(thickness 0.15)
				)
			)
		)
		(property "Author" "Antmicro"
			(at 309.88 119.38 0)
			(effects
				(font
					(size 1.27 1.27)
					(thickness 0.15)
				)
				(justify left bottom)
				(hide yes)
			)
		)
		(property "License" "Apache-2.0"
			(at 309.88 121.92 0)
			(effects
				(font
					(size 1.27 1.27)
					(thickness 0.15)
				)
				(justify left bottom)
				(hide yes)
			)
		)
		(pin "1"
		)
		(pin "2"
		)
		(pin "3"
		)
		(pin "9"
		)
		(pin "5"
		)
		(pin "6"
		)
		(pin "8"
		)
		(pin "4"
		)
		(pin "7"
		)
		(instances
			(project "OCuLink to 10GbE adapter"
				(path ""
					(reference "U3")
					(unit 1)
				)
			)
		)
	)
	(symbol
		(lib_id "antmicroCapacitors0603:C_22u_16V_0603")
		(at 364.49 76.2 90)
		(unit 1)
		(exclude_from_sim no)
		(in_bom yes)
		(on_board yes)
		(dnp no)
		(property "Reference" "C204"
			(at 366.268 72.39 90)
			(effects
				(font
					(size 1.27 1.27)
					(thickness 0.15)
				)
				(justify right)
			)
		)
		(property "Value" "C_22u_16V_0603"
			(at 374.65 55.88 0)
			(effects
				(font
					(size 1.27 1.27)
					(thickness 0.15)
				)
				(justify left bottom)
				(hide yes)
			)
		)
		(property "Footprint" "antmicro-footprints:C_0603_1608Metric_EIA"
			(at 377.19 55.88 0)
			(effects
				(font
					(size 1.27 1.27)
					(thickness 0.15)
				)
				(justify left bottom)
				(hide yes)
			)
		)
		(property "Datasheet" "https://product.samsungsem.com/mlcc/CL10A226MO7JZN.do"
			(at 379.73 55.88 0)
			(effects
				(font
					(size 1.27 1.27)
					(thickness 0.15)
				)
				(justify left bottom)
				(hide yes)
			)
		)
		(property "Description" "SMD Multilayer Ceramic Capacitor"
			(at 364.49 76.2 0)
			(effects
				(font
					(size 1.27 1.27)
				)
				(hide yes)
			)
		)
		(property "MPN" "CL10A226MO7JZNC"
			(at 382.27 55.88 0)
			(effects
				(font
					(size 1.27 1.27)
					(thickness 0.15)
				)
				(justify left bottom)
				(hide yes)
			)
		)
		(property "Manufacturer" "Samsung Electro-Mechanics"
			(at 384.81 55.88 0)
			(effects
				(font
					(size 1.27 1.27)
					(thickness 0.15)
				)
				(justify left bottom)
				(hide yes)
			)
		)
		(property "License" "Apache-2.0"
			(at 387.35 55.88 0)
			(effects
				(font
					(size 1.27 1.27)
					(thickness 0.15)
				)
				(justify left bottom)
				(hide yes)
			)
		)
		(property "Author" "Antmicro"
			(at 389.89 55.88 0)
			(effects
				(font
					(size 1.27 1.27)
					(thickness 0.15)
				)
				(justify left bottom)
				(hide yes)
			)
		)
		(property "Val" "22u"
			(at 366.268 74.93 90)
			(effects
				(font
					(size 1.27 1.27)
					(thickness 0.15)
				)
				(justify right)
			)
		)
		(property "Voltage" "16V"
			(at 367.03 76.1935 90)
			(effects
				(font
					(size 1.27 1.27)
				)
				(justify right)
				(hide yes)
			)
		)
		(property "Dielectric" ""
			(at 394.97 55.88 0)
			(effects
				(font
					(size 1.27 1.27)
				)
				(justify left bottom)
				(hide yes)
			)
		)
		(property "Public" "False"
			(at 397.51 55.88 0)
			(effects
				(font
					(size 1.27 1.27)
				)
				(justify left bottom)
				(hide yes)
			)
		)
		(pin "2"
		)
		(pin "1"
		)
		(instances
			(project "OCuLink to 10GbE adapter"
				(path ""
					(reference "C204")
					(unit 1)
				)
			)
		)
	)
	(symbol
		(lib_id "antmicroCapacitors0402:C_100n_0402")
		(at 237.49 76.2 270)
		(mirror x)
		(unit 1)
		(exclude_from_sim no)
		(in_bom yes)
		(on_board yes)
		(dnp no)
		(property "Reference" "C14"
			(at 235.712 72.39 90)
			(effects
				(font
					(size 1.27 1.27)
					(thickness 0.15)
				)
				(justify right)
			)
		)
		(property "Value" "C_100n_0402"
			(at 227.33 55.88 0)
			(effects
				(font
					(size 1.27 1.27)
					(thickness 0.15)
				)
				(justify left bottom)
				(hide yes)
			)
		)
		(property "Footprint" "antmicro-footprints:C_0402_1005Metric"
			(at 224.79 55.88 0)
			(effects
				(font
					(size 1.27 1.27)
					(thickness 0.15)
				)
				(justify left bottom)
				(hide yes)
			)
		)
		(property "Datasheet" "https://www.murata.com/products/productdetail?partno=GRM155R61H104KE14%23"
			(at 222.25 55.88 0)
			(effects
				(font
					(size 1.27 1.27)
					(thickness 0.15)
				)
				(justify left bottom)
				(hide yes)
			)
		)
		(property "Description" "SMD Multilayer Ceramic Capacitor, 0.1 µF, 50 V, 0402 [1005 Metric], ± 10%, X5R, GRM Series"
			(at 204.47 55.88 0)
			(effects
				(font
					(size 1.27 1.27)
				)
				(justify left bottom)
				(hide yes)
			)
		)
		(property "MPN" "GRM155R61H104KE14D"
			(at 219.71 55.88 0)
			(effects
				(font
					(size 1.27 1.27)
					(thickness 0.15)
				)
				(justify left bottom)
				(hide yes)
			)
		)
		(property "Manufacturer" "Murata"
			(at 217.17 55.88 0)
			(effects
				(font
					(size 1.27 1.27)
					(thickness 0.15)
				)
				(justify left bottom)
				(hide yes)
			)
		)
		(property "License" "Apache-2.0"
			(at 214.63 55.88 0)
			(effects
				(font
					(size 1.27 1.27)
					(thickness 0.15)
				)
				(justify left bottom)
				(hide yes)
			)
		)
		(property "Author" "Antmicro"
			(at 212.09 55.88 0)
			(effects
				(font
					(size 1.27 1.27)
					(thickness 0.15)
				)
				(justify left bottom)
				(hide yes)
			)
		)
		(property "Val" "100n"
			(at 235.712 74.93 90)
			(effects
				(font
					(size 1.27 1.27)
					(thickness 0.15)
				)
				(justify right)
			)
		)
		(property "Voltage" "50V"
			(at 209.55 55.88 0)
			(effects
				(font
					(size 1.27 1.27)
				)
				(justify left bottom)
				(hide yes)
			)
		)
		(property "Dielectric" "X5R"
			(at 207.01 55.88 0)
			(effects
				(font
					(size 1.27 1.27)
				)
				(justify left bottom)
				(hide yes)
			)
		)
		(pin "1"
		)
		(pin "2"
		)
		(instances
			(project ""
				(path ""
					(reference "C14")
					(unit 1)
				)
			)
		)
	)
	(symbol
		(lib_id "antmicropower:GND")
		(at 237.49 43.18 0)
		(unit 1)
		(exclude_from_sim no)
		(in_bom yes)
		(on_board yes)
		(dnp no)
		(property "Reference" "#PWR06"
			(at 246.38 45.72 0)
			(effects
				(font
					(size 1.27 1.27)
					(thickness 0.15)
				)
				(justify left bottom)
				(hide yes)
			)
		)
		(property "Value" "GND"
			(at 237.49 46.99 0)
			(effects
				(font
					(size 1.27 1.27)
					(thickness 0.15)
				)
			)
		)
		(property "Footprint" ""
			(at 246.38 50.8 0)
			(effects
				(font
					(size 1.27 1.27)
					(thickness 0.15)
				)
				(justify left bottom)
				(hide yes)
			)
		)
		(property "Datasheet" ""
			(at 246.38 55.88 0)
			(effects
				(font
					(size 1.27 1.27)
					(thickness 0.15)
				)
				(justify left bottom)
				(hide yes)
			)
		)
		(property "Description" ""
			(at 237.49 43.18 0)
			(effects
				(font
					(size 1.27 1.27)
				)
				(hide yes)
			)
		)
		(property "Author" "Antmicro"
			(at 246.38 50.8 0)
			(effects
				(font
					(size 1.27 1.27)
					(thickness 0.15)
				)
				(justify left bottom)
				(hide yes)
			)
		)
		(property "License" "Apache-2.0"
			(at 246.38 53.34 0)
			(effects
				(font
					(size 1.27 1.27)
					(thickness 0.15)
				)
				(justify left bottom)
				(hide yes)
			)
		)
		(pin "1"
		)
		(instances
			(project "OCuLink to 10GbE adapter"
				(path ""
					(reference "#PWR06")
					(unit 1)
				)
			)
		)
	)
	(symbol
		(lib_id "antmicroCapacitors0402:C_1u_25V_0402")
		(at 247.65 38.1 270)
		(mirror x)
		(unit 1)
		(exclude_from_sim no)
		(in_bom yes)
		(on_board yes)
		(dnp no)
		(property "Reference" "C6"
			(at 245.872 34.29 90)
			(effects
				(font
					(size 1.27 1.27)
					(thickness 0.15)
				)
				(justify right)
			)
		)
		(property "Value" "C_1u_25V_0402"
			(at 237.49 17.78 0)
			(effects
				(font
					(size 1.27 1.27)
					(thickness 0.15)
				)
				(justify left bottom)
				(hide yes)
			)
		)
		(property "Footprint" "antmicro-footprints:C_0402_1005Metric"
			(at 234.95 17.78 0)
			(effects
				(font
					(size 1.27 1.27)
					(thickness 0.15)
				)
				(justify left bottom)
				(hide yes)
			)
		)
		(property "Datasheet" "https://www.murata.com/products/productdetail?partno=GRM155R61E105KE11%23"
			(at 232.41 17.78 0)
			(effects
				(font
					(size 1.27 1.27)
					(thickness 0.15)
				)
				(justify left bottom)
				(hide yes)
			)
		)
		(property "Description" "SMD Multilayer Ceramic Capacitor, 1 µF, 25 V, 0402 [1005 Metric], ± 10%, X5R, GRM Series"
			(at 214.63 17.78 0)
			(effects
				(font
					(size 1.27 1.27)
				)
				(justify left bottom)
				(hide yes)
			)
		)
		(property "MPN" "GRM155R61E105KE11J"
			(at 229.87 17.78 0)
			(effects
				(font
					(size 1.27 1.27)
					(thickness 0.15)
				)
				(justify left bottom)
				(hide yes)
			)
		)
		(property "Manufacturer" "Murata"
			(at 227.33 17.78 0)
			(effects
				(font
					(size 1.27 1.27)
					(thickness 0.15)
				)
				(justify left bottom)
				(hide yes)
			)
		)
		(property "License" "Apache-2.0"
			(at 224.79 17.78 0)
			(effects
				(font
					(size 1.27 1.27)
					(thickness 0.15)
				)
				(justify left bottom)
				(hide yes)
			)
		)
		(property "Author" "Antmicro"
			(at 222.25 17.78 0)
			(effects
				(font
					(size 1.27 1.27)
					(thickness 0.15)
				)
				(justify left bottom)
				(hide yes)
			)
		)
		(property "Val" "1u"
			(at 245.872 36.83 90)
			(effects
				(font
					(size 1.27 1.27)
					(thickness 0.15)
				)
				(justify right)
			)
		)
		(property "Voltage" "25V"
			(at 219.71 17.78 0)
			(effects
				(font
					(size 1.27 1.27)
				)
				(justify left bottom)
				(hide yes)
			)
		)
		(property "Dielectric" "X5R"
			(at 217.17 17.78 0)
			(effects
				(font
					(size 1.27 1.27)
				)
				(justify left bottom)
				(hide yes)
			)
		)
		(pin "2"
		)
		(pin "1"
		)
		(instances
			(project ""
				(path ""
					(reference "C6")
					(unit 1)
				)
			)
		)
	)
	(symbol
		(lib_id "antmicroCapacitors0603:C_22u_16V_0603")
		(at 364.49 38.1 90)
		(unit 1)
		(exclude_from_sim no)
		(in_bom yes)
		(on_board yes)
		(dnp no)
		(property "Reference" "C205"
			(at 366.268 34.29 90)
			(effects
				(font
					(size 1.27 1.27)
					(thickness 0.15)
				)
				(justify right)
			)
		)
		(property "Value" "C_22u_16V_0603"
			(at 374.65 17.78 0)
			(effects
				(font
					(size 1.27 1.27)
					(thickness 0.15)
				)
				(justify left bottom)
				(hide yes)
			)
		)
		(property "Footprint" "antmicro-footprints:C_0603_1608Metric_EIA"
			(at 377.19 17.78 0)
			(effects
				(font
					(size 1.27 1.27)
					(thickness 0.15)
				)
				(justify left bottom)
				(hide yes)
			)
		)
		(property "Datasheet" "https://product.samsungsem.com/mlcc/CL10A226MO7JZN.do"
			(at 379.73 17.78 0)
			(effects
				(font
					(size 1.27 1.27)
					(thickness 0.15)
				)
				(justify left bottom)
				(hide yes)
			)
		)
		(property "Description" "SMD Multilayer Ceramic Capacitor"
			(at 364.49 38.1 0)
			(effects
				(font
					(size 1.27 1.27)
				)
				(hide yes)
			)
		)
		(property "MPN" "CL10A226MO7JZNC"
			(at 382.27 17.78 0)
			(effects
				(font
					(size 1.27 1.27)
					(thickness 0.15)
				)
				(justify left bottom)
				(hide yes)
			)
		)
		(property "Manufacturer" "Samsung Electro-Mechanics"
			(at 384.81 17.78 0)
			(effects
				(font
					(size 1.27 1.27)
					(thickness 0.15)
				)
				(justify left bottom)
				(hide yes)
			)
		)
		(property "License" "Apache-2.0"
			(at 387.35 17.78 0)
			(effects
				(font
					(size 1.27 1.27)
					(thickness 0.15)
				)
				(justify left bottom)
				(hide yes)
			)
		)
		(property "Author" "Antmicro"
			(at 389.89 17.78 0)
			(effects
				(font
					(size 1.27 1.27)
					(thickness 0.15)
				)
				(justify left bottom)
				(hide yes)
			)
		)
		(property "Val" "22u"
			(at 366.268 36.83 90)
			(effects
				(font
					(size 1.27 1.27)
					(thickness 0.15)
				)
				(justify right)
			)
		)
		(property "Voltage" "16V"
			(at 367.03 38.0935 90)
			(effects
				(font
					(size 1.27 1.27)
				)
				(justify right)
				(hide yes)
			)
		)
		(property "Dielectric" ""
			(at 394.97 17.78 0)
			(effects
				(font
					(size 1.27 1.27)
				)
				(justify left bottom)
				(hide yes)
			)
		)
		(property "Public" "False"
			(at 397.51 17.78 0)
			(effects
				(font
					(size 1.27 1.27)
				)
				(justify left bottom)
				(hide yes)
			)
		)
		(pin "2"
		)
		(pin "1"
		)
		(instances
			(project "OCuLink to 10GbE adapter"
				(path ""
					(reference "C205")
					(unit 1)
				)
			)
		)
	)
	(symbol
		(lib_id "antmicropower:GND")
		(at 332.74 157.48 0)
		(unit 1)
		(exclude_from_sim no)
		(in_bom yes)
		(on_board yes)
		(dnp no)
		(property "Reference" "#PWR042"
			(at 341.63 160.02 0)
			(effects
				(font
					(size 1.27 1.27)
					(thickness 0.15)
				)
				(justify left bottom)
				(hide yes)
			)
		)
		(property "Value" "GND"
			(at 332.74 161.29 0)
			(effects
				(font
					(size 1.27 1.27)
					(thickness 0.15)
				)
			)
		)
		(property "Footprint" ""
			(at 341.63 165.1 0)
			(effects
				(font
					(size 1.27 1.27)
					(thickness 0.15)
				)
				(justify left bottom)
				(hide yes)
			)
		)
		(property "Datasheet" ""
			(at 341.63 170.18 0)
			(effects
				(font
					(size 1.27 1.27)
					(thickness 0.15)
				)
				(justify left bottom)
				(hide yes)
			)
		)
		(property "Description" ""
			(at 332.74 157.48 0)
			(effects
				(font
					(size 1.27 1.27)
				)
				(hide yes)
			)
		)
		(property "Author" "Antmicro"
			(at 341.63 165.1 0)
			(effects
				(font
					(size 1.27 1.27)
					(thickness 0.15)
				)
				(justify left bottom)
				(hide yes)
			)
		)
		(property "License" "Apache-2.0"
			(at 341.63 167.64 0)
			(effects
				(font
					(size 1.27 1.27)
					(thickness 0.15)
				)
				(justify left bottom)
				(hide yes)
			)
		)
		(pin "1"
		)
		(instances
			(project "OCuLink to 10GbE adapter"
				(path ""
					(reference "#PWR042")
					(unit 1)
				)
			)
		)
	)
	(symbol
		(lib_id "antmicropower:GND")
		(at 354.33 195.58 0)
		(unit 1)
		(exclude_from_sim no)
		(in_bom yes)
		(on_board yes)
		(dnp no)
		(property "Reference" "#PWR060"
			(at 363.22 198.12 0)
			(effects
				(font
					(size 1.27 1.27)
					(thickness 0.15)
				)
				(justify left bottom)
				(hide yes)
			)
		)
		(property "Value" "GND"
			(at 354.33 199.39 0)
			(effects
				(font
					(size 1.27 1.27)
					(thickness 0.15)
				)
			)
		)
		(property "Footprint" ""
			(at 363.22 203.2 0)
			(effects
				(font
					(size 1.27 1.27)
					(thickness 0.15)
				)
				(justify left bottom)
				(hide yes)
			)
		)
		(property "Datasheet" ""
			(at 363.22 208.28 0)
			(effects
				(font
					(size 1.27 1.27)
					(thickness 0.15)
				)
				(justify left bottom)
				(hide yes)
			)
		)
		(property "Description" ""
			(at 354.33 195.58 0)
			(effects
				(font
					(size 1.27 1.27)
				)
				(hide yes)
			)
		)
		(property "Author" "Antmicro"
			(at 363.22 203.2 0)
			(effects
				(font
					(size 1.27 1.27)
					(thickness 0.15)
				)
				(justify left bottom)
				(hide yes)
			)
		)
		(property "License" "Apache-2.0"
			(at 363.22 205.74 0)
			(effects
				(font
					(size 1.27 1.27)
					(thickness 0.15)
				)
				(justify left bottom)
				(hide yes)
			)
		)
		(pin "1"
		)
		(instances
			(project "OCuLink to 10GbE adapter"
				(path ""
					(reference "#PWR060")
					(unit 1)
				)
			)
		)
	)
	(symbol
		(lib_id "antmicroUSBConnectors:USB-C_GCT_USB4105-GF-A")
		(at 50.8 120.65 0)
		(unit 1)
		(exclude_from_sim no)
		(in_bom yes)
		(on_board yes)
		(dnp no)
		(fields_autoplaced yes)
		(property "Reference" "J2"
			(at 37.465 113.03 0)
			(effects
				(font
					(size 1.27 1.27)
					(thickness 0.15)
				)
			)
		)
		(property "Value" "USB-C_GCT_USB4105-GF-A"
			(at 37.465 115.57 0)
			(effects
				(font
					(size 1.27 1.27)
					(thickness 0.15)
				)
				(hide yes)
			)
		)
		(property "Footprint" "antmicro-footprints:USB-C_Receptacle_GCT_USB4105-GF-A"
			(at 88.9 128.27 0)
			(effects
				(font
					(size 1.27 1.27)
					(thickness 0.15)
				)
				(justify left bottom)
				(hide yes)
			)
		)
		(property "Datasheet" "https://gct.co/files/drawings/usb4105.pdf"
			(at 88.9 130.81 0)
			(effects
				(font
					(size 1.27 1.27)
					(thickness 0.15)
				)
				(justify left bottom)
				(hide yes)
			)
		)
		(property "Description" "USB-C (USB TYPE-C) USB 2.0 Receptacle Connector 24 (16+8 Dummy) Position Surface Mount, Right Angle"
			(at 50.8 120.65 0)
			(effects
				(font
					(size 1.27 1.27)
				)
				(hide yes)
			)
		)
		(property "Manufacturer" "GCT"
			(at 88.9 133.35 0)
			(effects
				(font
					(size 1.27 1.27)
					(thickness 0.15)
				)
				(justify left bottom)
				(hide yes)
			)
		)
		(property "MPN" "USB4105-GF-A"
			(at 37.465 115.57 0)
			(effects
				(font
					(size 1.27 1.27)
					(thickness 0.15)
				)
			)
		)
		(property "Author" "Antmicro"
			(at 88.9 138.43 0)
			(effects
				(font
					(size 1.27 1.27)
					(thickness 0.15)
				)
				(justify left bottom)
				(hide yes)
			)
		)
		(property "License" "Apache-2.0"
			(at 88.9 140.97 0)
			(effects
				(font
					(size 1.27 1.27)
					(thickness 0.15)
				)
				(justify left bottom)
				(hide yes)
			)
		)
		(pin "A7"
		)
		(pin "B6"
		)
		(pin "SH"
		)
		(pin "B7"
		)
		(pin "B8"
		)
		(pin "A8"
		)
		(pin "B1"
		)
		(pin "A1"
		)
		(pin "A12"
		)
		(pin "B12"
		)
		(pin "A6"
		)
		(pin "B4"
		)
		(pin "B9"
		)
		(pin "B5"
		)
		(pin "A5"
		)
		(pin "A9"
		)
		(pin "A4"
		)
		(instances
			(project "OCuLink to 10GbE adapter"
				(path ""
					(reference "J2")
					(unit 1)
				)
			)
		)
	)
	(symbol
		(lib_id "antmicropower:GND")
		(at 354.33 119.38 0)
		(unit 1)
		(exclude_from_sim no)
		(in_bom yes)
		(on_board yes)
		(dnp no)
		(property "Reference" "#PWR034"
			(at 363.22 121.92 0)
			(effects
				(font
					(size 1.27 1.27)
					(thickness 0.15)
				)
				(justify left bottom)
				(hide yes)
			)
		)
		(property "Value" "GND"
			(at 354.33 123.19 0)
			(effects
				(font
					(size 1.27 1.27)
					(thickness 0.15)
				)
			)
		)
		(property "Footprint" ""
			(at 363.22 127 0)
			(effects
				(font
					(size 1.27 1.27)
					(thickness 0.15)
				)
				(justify left bottom)
				(hide yes)
			)
		)
		(property "Datasheet" ""
			(at 363.22 132.08 0)
			(effects
				(font
					(size 1.27 1.27)
					(thickness 0.15)
				)
				(justify left bottom)
				(hide yes)
			)
		)
		(property "Description" ""
			(at 354.33 119.38 0)
			(effects
				(font
					(size 1.27 1.27)
				)
				(hide yes)
			)
		)
		(property "Author" "Antmicro"
			(at 363.22 127 0)
			(effects
				(font
					(size 1.27 1.27)
					(thickness 0.15)
				)
				(justify left bottom)
				(hide yes)
			)
		)
		(property "License" "Apache-2.0"
			(at 363.22 129.54 0)
			(effects
				(font
					(size 1.27 1.27)
					(thickness 0.15)
				)
				(justify left bottom)
				(hide yes)
			)
		)
		(pin "1"
		)
		(instances
			(project "OCuLink to 10GbE adapter"
				(path ""
					(reference "#PWR034")
					(unit 1)
				)
			)
		)
	)
	(symbol
		(lib_id "antmicropower:GND")
		(at 364.49 81.28 0)
		(unit 1)
		(exclude_from_sim no)
		(in_bom yes)
		(on_board yes)
		(dnp no)
		(property "Reference" "#PWR0266"
			(at 373.38 83.82 0)
			(effects
				(font
					(size 1.27 1.27)
					(thickness 0.15)
				)
				(justify left bottom)
				(hide yes)
			)
		)
		(property "Value" "GND"
			(at 364.49 85.09 0)
			(effects
				(font
					(size 1.27 1.27)
					(thickness 0.15)
				)
			)
		)
		(property "Footprint" ""
			(at 373.38 88.9 0)
			(effects
				(font
					(size 1.27 1.27)
					(thickness 0.15)
				)
				(justify left bottom)
				(hide yes)
			)
		)
		(property "Datasheet" ""
			(at 373.38 93.98 0)
			(effects
				(font
					(size 1.27 1.27)
					(thickness 0.15)
				)
				(justify left bottom)
				(hide yes)
			)
		)
		(property "Description" ""
			(at 364.49 81.28 0)
			(effects
				(font
					(size 1.27 1.27)
				)
				(hide yes)
			)
		)
		(property "Author" "Antmicro"
			(at 373.38 88.9 0)
			(effects
				(font
					(size 1.27 1.27)
					(thickness 0.15)
				)
				(justify left bottom)
				(hide yes)
			)
		)
		(property "License" "Apache-2.0"
			(at 373.38 91.44 0)
			(effects
				(font
					(size 1.27 1.27)
					(thickness 0.15)
				)
				(justify left bottom)
				(hide yes)
			)
		)
		(pin "1"
		)
		(instances
			(project "OCuLink to 10GbE adapter"
				(path ""
					(reference "#PWR0266")
					(unit 1)
				)
			)
		)
	)
	(symbol
		(lib_id "antmicropower:VDD")
		(at 387.35 238.76 90)
		(unit 1)
		(exclude_from_sim no)
		(in_bom yes)
		(on_board yes)
		(dnp no)
		(fields_autoplaced yes)
		(property "Reference" "#PWR0309"
			(at 391.16 238.76 0)
			(effects
				(font
					(size 1.27 1.27)
				)
				(hide yes)
			)
		)
		(property "Value" "DVDD"
			(at 383.54 238.7599 90)
			(effects
				(font
					(size 1.27 1.27)
				)
				(justify left)
			)
		)
		(property "Footprint" ""
			(at 387.35 238.76 0)
			(effects
				(font
					(size 1.27 1.27)
				)
				(hide yes)
			)
		)
		(property "Datasheet" ""
			(at 387.35 238.76 0)
			(effects
				(font
					(size 1.27 1.27)
				)
				(hide yes)
			)
		)
		(property "Description" ""
			(at 387.35 238.76 0)
			(effects
				(font
					(size 1.27 1.27)
				)
				(hide yes)
			)
		)
		(pin "1"
		)
		(instances
			(project "oculink-to-10gbe-adapter"
				(path ""
					(reference "#PWR0309")
					(unit 1)
				)
			)
		)
	)
	(symbol
		(lib_id "antmicroTVSDiodes:PESD5Z5_0F")
		(at 67.31 137.16 90)
		(mirror x)
		(unit 1)
		(exclude_from_sim no)
		(in_bom yes)
		(on_board yes)
		(dnp no)
		(property "Reference" "D10"
			(at 64.77 138.43 90)
			(effects
				(font
					(size 1.27 1.27)
					(thickness 0.15)
				)
				(justify left)
			)
		)
		(property "Value" "PESD5Z5_0F"
			(at 80.01 152.4 0)
			(effects
				(font
					(size 1.27 1.27)
					(thickness 0.15)
				)
				(justify left bottom)
				(hide yes)
			)
		)
		(property "Footprint" "antmicro-footprints:SOD-523"
			(at 72.39 152.4 0)
			(effects
				(font
					(size 1.27 1.27)
					(thickness 0.15)
				)
				(justify left bottom)
				(hide yes)
			)
		)
		(property "Datasheet" "https://assets.nexperia.com/documents/data-sheet/PESD5Z5_0.pdf"
			(at 74.93 152.4 0)
			(effects
				(font
					(size 1.27 1.27)
					(thickness 0.15)
				)
				(justify left bottom)
				(hide yes)
			)
		)
		(property "Description" "Unidirectional TVS, 30 kV,  SOD-523, 5 V, 89 pF"
			(at 87.63 152.4 0)
			(effects
				(font
					(size 1.27 1.27)
				)
				(justify left bottom)
				(hide yes)
			)
		)
		(property "Manufacturer" "Nexperia"
			(at 77.47 152.4 0)
			(effects
				(font
					(size 1.27 1.27)
					(thickness 0.15)
				)
				(justify left bottom)
				(hide yes)
			)
		)
		(property "MPN" "PESD5Z5.0F"
			(at 64.77 140.97 90)
			(effects
				(font
					(size 1.27 1.27)
					(thickness 0.15)
				)
				(justify left)
			)
		)
		(property "Author" "Antmicro"
			(at 82.55 152.4 0)
			(effects
				(font
					(size 1.27 1.27)
					(thickness 0.15)
				)
				(justify left bottom)
				(hide yes)
			)
		)
		(property "License" "Apache-2.0"
			(at 85.09 152.4 0)
			(effects
				(font
					(size 1.27 1.27)
					(thickness 0.15)
				)
				(justify left bottom)
				(hide yes)
			)
		)
		(pin "2"
		)
		(pin "1"
		)
		(instances
			(project "OCuLink to 10GbE adapter"
				(path ""
					(reference "D10")
					(unit 1)
				)
			)
		)
	)
	(symbol
		(lib_id "antmicroTransistorsBipolarSingle:DTC014T_SOT-416")
		(at 220.98 238.76 0)
		(unit 1)
		(exclude_from_sim no)
		(in_bom yes)
		(on_board yes)
		(dnp no)
		(property "Reference" "Q7"
			(at 230.378 240.03 0)
			(effects
				(font
					(size 1.27 1.27)
					(thickness 0.15)
				)
				(justify left)
			)
		)
		(property "Value" "DTC014T_SOT-416"
			(at 246.38 246.38 0)
			(effects
				(font
					(size 1.27 1.27)
					(thickness 0.15)
				)
				(justify left bottom)
				(hide yes)
			)
		)
		(property "Footprint" "antmicro-footprints:SOT-416"
			(at 246.38 248.92 0)
			(effects
				(font
					(size 1.27 1.27)
					(thickness 0.15)
				)
				(justify left bottom)
				(hide yes)
			)
		)
		(property "Datasheet" "https://www.rohm.com/datasheet?p=DTC014TEB&dist=Mouser&media=referral&source=mouser.com&campaign=Mouser"
			(at 246.38 251.46 0)
			(effects
				(font
					(size 1.27 1.27)
					(thickness 0.15)
				)
				(justify left bottom)
				(hide yes)
			)
		)
		(property "Description" "Bipolar (BJT) Single Transistor with built-in base resistor, NPN, 50V, 100mA, 150mW, SOT-416FL, Surface Mount"
			(at 246.38 264.16 0)
			(effects
				(font
					(size 1.27 1.27)
				)
				(justify left bottom)
				(hide yes)
			)
		)
		(property "Manufacturer" "ROHM Semiconductor"
			(at 246.38 254 0)
			(effects
				(font
					(size 1.27 1.27)
					(thickness 0.15)
				)
				(justify left bottom)
				(hide yes)
			)
		)
		(property "MPN" "DTC014TEBTL"
			(at 230.378 242.57 0)
			(effects
				(font
					(size 1.27 1.27)
					(thickness 0.15)
				)
				(justify left)
			)
		)
		(property "Author" "Antmicro"
			(at 246.38 259.08 0)
			(effects
				(font
					(size 1.27 1.27)
					(thickness 0.15)
				)
				(justify left bottom)
				(hide yes)
			)
		)
		(property "License" "Apache-2.0"
			(at 246.38 261.62 0)
			(effects
				(font
					(size 1.27 1.27)
					(thickness 0.15)
				)
				(justify left bottom)
				(hide yes)
			)
		)
		(pin "1"
		)
		(pin "2"
		)
		(pin "3"
		)
		(instances
			(project "oculink-to-10gbe-adapter"
				(path ""
					(reference "Q7")
					(unit 1)
				)
			)
		)
	)
	(symbol
		(lib_id "antmicroTestPoints:TP_1mm_SMD")
		(at 391.16 220.98 0)
		(unit 1)
		(exclude_from_sim no)
		(in_bom no)
		(on_board yes)
		(dnp no)
		(fields_autoplaced yes)
		(property "Reference" "TP27"
			(at 396.24 220.98 0)
			(effects
				(font
					(size 1.27 1.27)
					(thickness 0.15)
				)
				(justify left)
			)
		)
		(property "Value" "TP_1mm_SMD"
			(at 406.4 228.6 0)
			(effects
				(font
					(size 1.27 1.27)
					(thickness 0.15)
				)
				(justify left bottom)
				(hide yes)
			)
		)
		(property "Footprint" "antmicro-footprints:TP_SMD_1mm"
			(at 406.4 231.14 0)
			(effects
				(font
					(size 1.27 1.27)
					(thickness 0.15)
				)
				(justify left bottom)
				(hide yes)
			)
		)
		(property "Datasheet" ""
			(at 408.94 233.68 0)
			(effects
				(font
					(size 1.27 1.27)
					(thickness 0.15)
				)
				(justify left bottom)
				(hide yes)
			)
		)
		(property "Description" "Test point 1mm SMD"
			(at 406.4 241.3 0)
			(effects
				(font
					(size 1.27 1.27)
				)
				(justify left bottom)
				(hide yes)
			)
		)
		(property "MPN" ""
			(at 391.16 220.98 0)
			(effects
				(font
					(size 1.27 1.27)
				)
				(hide yes)
			)
		)
		(property "Manufacturer" ""
			(at 391.16 220.98 0)
			(effects
				(font
					(size 1.27 1.27)
				)
				(hide yes)
			)
		)
		(property "Author" "Antmicro"
			(at 406.4 236.22 0)
			(effects
				(font
					(size 1.27 1.27)
					(thickness 0.15)
				)
				(justify left bottom)
				(hide yes)
			)
		)
		(property "License" "Apache-2.0"
			(at 406.4 238.76 0)
			(effects
				(font
					(size 1.27 1.27)
					(thickness 0.15)
				)
				(justify left bottom)
				(hide yes)
			)
		)
		(pin "1"
		)
		(instances
			(project ""
				(path ""
					(reference "TP27")
					(unit 1)
				)
			)
		)
	)
	(symbol
		(lib_id "antmicroCapacitors0402:C_100n_0402")
		(at 374.65 114.3 90)
		(unit 1)
		(exclude_from_sim no)
		(in_bom yes)
		(on_board yes)
		(dnp no)
		(property "Reference" "C27"
			(at 376.428 110.49 90)
			(effects
				(font
					(size 1.27 1.27)
					(thickness 0.15)
				)
				(justify right)
			)
		)
		(property "Value" "C_100n_0402"
			(at 384.81 93.98 0)
			(effects
				(font
					(size 1.27 1.27)
					(thickness 0.15)
				)
				(justify left bottom)
				(hide yes)
			)
		)
		(property "Footprint" "antmicro-footprints:C_0402_1005Metric"
			(at 387.35 93.98 0)
			(effects
				(font
					(size 1.27 1.27)
					(thickness 0.15)
				)
				(justify left bottom)
				(hide yes)
			)
		)
		(property "Datasheet" "https://www.murata.com/products/productdetail?partno=GRM155R61H104KE14%23"
			(at 389.89 93.98 0)
			(effects
				(font
					(size 1.27 1.27)
					(thickness 0.15)
				)
				(justify left bottom)
				(hide yes)
			)
		)
		(property "Description" "SMD Multilayer Ceramic Capacitor, 0.1 µF, 50 V, 0402 [1005 Metric], ± 10%, X5R, GRM Series"
			(at 407.67 93.98 0)
			(effects
				(font
					(size 1.27 1.27)
				)
				(justify left bottom)
				(hide yes)
			)
		)
		(property "MPN" "GRM155R61H104KE14D"
			(at 392.43 93.98 0)
			(effects
				(font
					(size 1.27 1.27)
					(thickness 0.15)
				)
				(justify left bottom)
				(hide yes)
			)
		)
		(property "Manufacturer" "Murata"
			(at 394.97 93.98 0)
			(effects
				(font
					(size 1.27 1.27)
					(thickness 0.15)
				)
				(justify left bottom)
				(hide yes)
			)
		)
		(property "License" "Apache-2.0"
			(at 397.51 93.98 0)
			(effects
				(font
					(size 1.27 1.27)
					(thickness 0.15)
				)
				(justify left bottom)
				(hide yes)
			)
		)
		(property "Author" "Antmicro"
			(at 400.05 93.98 0)
			(effects
				(font
					(size 1.27 1.27)
					(thickness 0.15)
				)
				(justify left bottom)
				(hide yes)
			)
		)
		(property "Val" "100n"
			(at 376.428 113.03 90)
			(effects
				(font
					(size 1.27 1.27)
					(thickness 0.15)
				)
				(justify right)
			)
		)
		(property "Voltage" "50V"
			(at 402.59 93.98 0)
			(effects
				(font
					(size 1.27 1.27)
				)
				(justify left bottom)
				(hide yes)
			)
		)
		(property "Dielectric" "X5R"
			(at 405.13 93.98 0)
			(effects
				(font
					(size 1.27 1.27)
				)
				(justify left bottom)
				(hide yes)
			)
		)
		(pin "1"
		)
		(pin "2"
		)
		(instances
			(project "OCuLink to 10GbE adapter"
				(path ""
					(reference "C27")
					(unit 1)
				)
			)
		)
	)
	(symbol
		(lib_id "antmicropower:GND")
		(at 344.17 119.38 0)
		(unit 1)
		(exclude_from_sim no)
		(in_bom yes)
		(on_board yes)
		(dnp no)
		(property "Reference" "#PWR033"
			(at 353.06 121.92 0)
			(effects
				(font
					(size 1.27 1.27)
					(thickness 0.15)
				)
				(justify left bottom)
				(hide yes)
			)
		)
		(property "Value" "GND"
			(at 344.17 123.19 0)
			(effects
				(font
					(size 1.27 1.27)
					(thickness 0.15)
				)
			)
		)
		(property "Footprint" ""
			(at 353.06 127 0)
			(effects
				(font
					(size 1.27 1.27)
					(thickness 0.15)
				)
				(justify left bottom)
				(hide yes)
			)
		)
		(property "Datasheet" ""
			(at 353.06 132.08 0)
			(effects
				(font
					(size 1.27 1.27)
					(thickness 0.15)
				)
				(justify left bottom)
				(hide yes)
			)
		)
		(property "Description" ""
			(at 344.17 119.38 0)
			(effects
				(font
					(size 1.27 1.27)
				)
				(hide yes)
			)
		)
		(property "Author" "Antmicro"
			(at 353.06 127 0)
			(effects
				(font
					(size 1.27 1.27)
					(thickness 0.15)
				)
				(justify left bottom)
				(hide yes)
			)
		)
		(property "License" "Apache-2.0"
			(at 353.06 129.54 0)
			(effects
				(font
					(size 1.27 1.27)
					(thickness 0.15)
				)
				(justify left bottom)
				(hide yes)
			)
		)
		(pin "1"
		)
		(instances
			(project "OCuLink to 10GbE adapter"
				(path ""
					(reference "#PWR033")
					(unit 1)
				)
			)
		)
	)
	(symbol
		(lib_id "antmicropower:VDD")
		(at 400.05 175.26 0)
		(unit 1)
		(exclude_from_sim no)
		(in_bom yes)
		(on_board yes)
		(dnp no)
		(property "Reference" "#PWR052"
			(at 400.05 179.07 0)
			(effects
				(font
					(size 1.27 1.27)
				)
				(hide yes)
			)
		)
		(property "Value" "DVDD"
			(at 400.05 171.45 0)
			(effects
				(font
					(size 1.27 1.27)
				)
			)
		)
		(property "Footprint" ""
			(at 400.05 175.26 0)
			(effects
				(font
					(size 1.27 1.27)
				)
				(hide yes)
			)
		)
		(property "Datasheet" ""
			(at 400.05 175.26 0)
			(effects
				(font
					(size 1.27 1.27)
				)
				(hide yes)
			)
		)
		(property "Description" ""
			(at 400.05 175.26 0)
			(effects
				(font
					(size 1.27 1.27)
				)
				(hide yes)
			)
		)
		(pin "1"
		)
		(instances
			(project "OCuLink to 10GbE adapter"
				(path ""
					(reference "#PWR052")
					(unit 1)
				)
			)
		)
	)
	(symbol
		(lib_id "antmicropower:VCC")
		(at 217.17 60.96 0)
		(unit 1)
		(exclude_from_sim no)
		(in_bom yes)
		(on_board yes)
		(dnp no)
		(property "Reference" "#PWR0353"
			(at 217.17 64.77 0)
			(effects
				(font
					(size 1.27 1.27)
				)
				(hide yes)
			)
		)
		(property "Value" "VCC"
			(at 217.17 57.15 0)
			(effects
				(font
					(size 1.27 1.27)
				)
			)
		)
		(property "Footprint" ""
			(at 217.17 60.96 0)
			(effects
				(font
					(size 1.27 1.27)
				)
				(hide yes)
			)
		)
		(property "Datasheet" ""
			(at 217.17 60.96 0)
			(effects
				(font
					(size 1.27 1.27)
				)
				(hide yes)
			)
		)
		(property "Description" ""
			(at 217.17 67.31 0)
			(effects
				(font
					(size 1.27 1.27)
				)
				(justify left bottom)
				(hide yes)
			)
		)
		(pin "1"
		)
		(instances
			(project "oculink-to-10gbe-adapter"
				(path ""
					(reference "#PWR0353")
					(unit 1)
				)
			)
		)
	)
	(symbol
		(lib_id "antmicropower:GND")
		(at 304.8 246.38 0)
		(unit 1)
		(exclude_from_sim no)
		(in_bom yes)
		(on_board yes)
		(dnp no)
		(property "Reference" "#PWR0332"
			(at 313.69 248.92 0)
			(effects
				(font
					(size 1.27 1.27)
					(thickness 0.15)
				)
				(justify left bottom)
				(hide yes)
			)
		)
		(property "Value" "GND"
			(at 304.8 250.19 0)
			(effects
				(font
					(size 1.27 1.27)
					(thickness 0.15)
				)
			)
		)
		(property "Footprint" ""
			(at 313.69 254 0)
			(effects
				(font
					(size 1.27 1.27)
					(thickness 0.15)
				)
				(justify left bottom)
				(hide yes)
			)
		)
		(property "Datasheet" ""
			(at 313.69 259.08 0)
			(effects
				(font
					(size 1.27 1.27)
					(thickness 0.15)
				)
				(justify left bottom)
				(hide yes)
			)
		)
		(property "Description" ""
			(at 304.8 246.38 0)
			(effects
				(font
					(size 1.27 1.27)
				)
				(hide yes)
			)
		)
		(property "Author" "Antmicro"
			(at 313.69 254 0)
			(effects
				(font
					(size 1.27 1.27)
					(thickness 0.15)
				)
				(justify left bottom)
				(hide yes)
			)
		)
		(property "License" "Apache-2.0"
			(at 313.69 256.54 0)
			(effects
				(font
					(size 1.27 1.27)
					(thickness 0.15)
				)
				(justify left bottom)
				(hide yes)
			)
		)
		(pin "1"
		)
		(instances
			(project "OCuLink to 10GbE adapter"
				(path ""
					(reference "#PWR0332")
					(unit 1)
				)
			)
		)
	)
	(sheet
		(at 96.52 116.84)
		(size 25.4 7.62)
		(exclude_from_sim no)
		(in_bom yes)
		(on_board yes)
		(dnp no)
		(fields_autoplaced yes)
		(stroke
			(width 0.1524)
			(type solid)
		)
		(fill
			(color 255 255 194 1.0000)
		)
		(property "Sheetname" "Ideal diode 2"
			(at 96.52 116.1284 0)
			(effects
				(font
					(size 1.27 1.27)
				)
				(justify left bottom)
			)
		)
		(property "Sheetfile" "ideal-diode.kicad_sch"
			(at 96.52 125.0446 0)
			(effects
				(font
					(size 1.27 1.27)
				)
				(justify left top)
			)
		)
		(pin "VIN" input
			(at 96.52 120.65 180)
			(effects
				(font
					(size 1.27 1.27)
				)
				(justify left)
			)
		)
		(pin "VOUT" output
			(at 121.92 120.65 0)
			(effects
				(font
					(size 1.27 1.27)
				)
				(justify right)
			)
		)
		(instances
			(project "oculink-to-10gbe-adapter"
				(path ""
					(page "13")
				)
			)
		)
	)
	(sheet
		(at 96.52 81.28)
		(size 25.4 7.62)
		(exclude_from_sim no)
		(in_bom yes)
		(on_board yes)
		(dnp no)
		(fields_autoplaced yes)
		(stroke
			(width 0.1524)
			(type solid)
		)
		(fill
			(color 255 255 194 1.0000)
		)
		(property "Sheetname" "Ideal diode 1"
			(at 96.52 80.5684 0)
			(effects
				(font
					(size 1.27 1.27)
				)
				(justify left bottom)
			)
		)
		(property "Sheetfile" "ideal-diode.kicad_sch"
			(at 96.52 89.4846 0)
			(effects
				(font
					(size 1.27 1.27)
				)
				(justify left top)
			)
		)
		(pin "VIN" input
			(at 96.52 85.09 180)
			(effects
				(font
					(size 1.27 1.27)
				)
				(justify left)
			)
		)
		(pin "VOUT" output
			(at 121.92 85.09 0)
			(effects
				(font
					(size 1.27 1.27)
				)
				(justify right)
			)
		)
		(instances
			(project "oculink-to-10gbe-adapter"
				(path ""
					(page "12")
				)
			)
		)
	)
)
